G04 ================== begin FILE IDENTIFICATION RECORD ==================*
G04 Layout Name:  12432-1.brd*
G04 Film Name:    TMASK*
G04 File Format:  Gerber RS274X*
G04 File Origin:  Cadence Allegro 16.2-S037*
G04 Origin Date:  Wed Oct 17 10:59:47 2012*
G04 *
G04 Layer:  VIA CLASS/SOLDERMASK_TOP*
G04 Layer:  PIN/SOLDERMASK_TOP*
G04 Layer:  PACKAGE GEOMETRY/SOLDERMASK_TOP*
G04 Layer:  DRAWING FORMAT/LAYER_PCB_STORY*
G04 Layer:  DRAWING FORMAT/LAYER_SOLDER_T*
G04 Layer:  BOARD GEOMETRY/SOLDERMASK_TOP*
G04 *
G04 Offset:    (0.00 0.00)*
G04 Mirror:    No*
G04 Mode:      Positive*
G04 Rotation:  0*
G04 FullContactRelief:  No*
G04 UndefLineWidth:     6.00*
G04 ================== end FILE IDENTIFICATION RECORD ====================*
%FSLAX35Y35*MOIN*%
%IR0*IPPOS*OFA0.00000B0.00000*MIA0B0*SFA1.00000B1.00000*%
%AMMACRO70*
4,1,40,.013,.017,
-.013,.017,
-.013695,.016939,
-.014368,.016759,
-.015,.016464,
-.015571,.016064,
-.016064,.015571,
-.016464,.015,
-.016759,.014368,
-.016939,.013695,
-.017,.013,
-.017,-.013,
-.016939,-.013695,
-.016759,-.014368,
-.016464,-.015,
-.016064,-.015571,
-.015571,-.016064,
-.015,-.016464,
-.014368,-.016759,
-.013695,-.016939,
-.013,-.017,
.013,-.017,
.013695,-.016939,
.014368,-.016759,
.015,-.016464,
.015571,-.016064,
.016064,-.015571,
.016464,-.015,
.016759,-.014368,
.016939,-.013695,
.017,-.013,
.017,.013,
.016939,.013695,
.016759,.014368,
.016464,.015,
.016064,.015571,
.015571,.016064,
.015,.016464,
.014368,.016759,
.013695,.016939,
.013,.017,
0.0*
%
%ADD70MACRO70*%
%AMMACRO43*
4,1,40,.017,-.013,
.017,.013,
.016939,.013695,
.016759,.014368,
.016464,.015,
.016064,.015571,
.015571,.016064,
.015,.016464,
.014368,.016759,
.013695,.016939,
.013,.017,
-.013,.017,
-.013695,.016939,
-.014368,.016759,
-.015,.016464,
-.015571,.016064,
-.016064,.015571,
-.016464,.015,
-.016759,.014368,
-.016939,.013695,
-.017,.013,
-.017,-.013,
-.016939,-.013695,
-.016759,-.014368,
-.016464,-.015,
-.016064,-.015571,
-.015571,-.016064,
-.015,-.016464,
-.014368,-.016759,
-.013695,-.016939,
-.013,-.017,
.013,-.017,
.013695,-.016939,
.014368,-.016759,
.015,-.016464,
.015571,-.016064,
.016064,-.015571,
.016464,-.015,
.016759,-.014368,
.016939,-.013695,
.017,-.013,
0.0*
%
%ADD43MACRO43*%
%ADD44O,.103X.06*%
%ADD86R,.23X.032*%
%ADD58R,.045X.11*%
%ADD57R,.11X.045*%
%ADD14R,.142X.028*%
%ADD36C,.022*%
%ADD22C,.032*%
%ADD45C,.073*%
%ADD24C,.028*%
%ADD13C,.091*%
%ADD38R,.208X.087*%
%ADD66R,.087X.208*%
%ADD11C,.086*%
%AMMACRO60*
4,1,40,-.007,-.0225,
-.008389,-.022378,
-.009736,-.022018,
-.011,-.021428,
-.012142,-.020628,
-.013128,-.019642,
-.013928,-.0185,
-.014518,-.017236,
-.014878,-.015889,
-.015,-.0145,
-.015,.0145,
-.014878,.015889,
-.014518,.017236,
-.013928,.0185,
-.013128,.019642,
-.012142,.020628,
-.011,.021428,
-.009736,.022018,
-.008389,.022378,
-.007,.0225,
.007,.0225,
.008389,.022378,
.009736,.022018,
.011,.021428,
.012142,.020628,
.013128,.019642,
.013928,.0185,
.014518,.017236,
.014878,.015889,
.015,.0145,
.015,-.0145,
.014878,-.015889,
.014518,-.017236,
.013928,-.0185,
.013128,-.019642,
.012142,-.020628,
.011,-.021428,
.009736,-.022018,
.008389,-.022378,
.007,-.0225,
-.007,-.0225,
0.0*
%
%ADD60MACRO60*%
%AMMACRO29*
4,1,40,.011,-.007,
.011,.007,
.010939,.007695,
.010759,.008368,
.010464,.009,
.010064,.009571,
.009571,.010064,
.009,.010464,
.008368,.010759,
.007695,.010939,
.007,.011,
-.007,.011,
-.007695,.010939,
-.008368,.010759,
-.009,.010464,
-.009571,.010064,
-.010064,.009571,
-.010464,.009,
-.010759,.008368,
-.010939,.007695,
-.011,.007,
-.011,-.007,
-.010939,-.007695,
-.010759,-.008368,
-.010464,-.009,
-.010064,-.009571,
-.009571,-.010064,
-.009,-.010464,
-.008368,-.010759,
-.007695,-.010939,
-.007,-.011,
.007,-.011,
.007695,-.010939,
.008368,-.010759,
.009,-.010464,
.009571,-.010064,
.010064,-.009571,
.010464,-.009,
.010759,-.008368,
.010939,-.007695,
.011,-.007,
0.0*
%
%ADD29MACRO29*%
%AMMACRO19*
4,1,40,.007,.011,
-.007,.011,
-.007695,.010939,
-.008368,.010759,
-.009,.010464,
-.009571,.010064,
-.010064,.009571,
-.010464,.009,
-.010759,.008368,
-.010939,.007695,
-.011,.007,
-.011,-.007,
-.010939,-.007695,
-.010759,-.008368,
-.010464,-.009,
-.010064,-.009571,
-.009571,-.010064,
-.009,-.010464,
-.008368,-.010759,
-.007695,-.010939,
-.007,-.011,
.007,-.011,
.007695,-.010939,
.008368,-.010759,
.009,-.010464,
.009571,-.010064,
.010064,-.009571,
.010464,-.009,
.010759,-.008368,
.010939,-.007695,
.011,-.007,
.011,.007,
.010939,.007695,
.010759,.008368,
.010464,.009,
.010064,.009571,
.009571,.010064,
.009,.010464,
.008368,.010759,
.007695,.010939,
.007,.011,
0.0*
%
%ADD19MACRO19*%
%AMMACRO31*
4,1,40,-.012,.008,
-.012,-.008,
-.011939,-.008695,
-.011759,-.009368,
-.011464,-.01,
-.011064,-.010571,
-.010571,-.011064,
-.01,-.011464,
-.009368,-.011759,
-.008695,-.011939,
-.008,-.012,
.008,-.012,
.008695,-.011939,
.009368,-.011759,
.01,-.011464,
.010571,-.011064,
.011064,-.010571,
.011464,-.01,
.011759,-.009368,
.011939,-.008695,
.012,-.008,
.012,.008,
.011939,.008695,
.011759,.009368,
.011464,.01,
.011064,.010571,
.010571,.011064,
.01,.011464,
.009368,.011759,
.008695,.011939,
.008,.012,
-.008,.012,
-.008695,.011939,
-.009368,.011759,
-.01,.011464,
-.010571,.011064,
-.011064,.010571,
-.011464,.01,
-.011759,.009368,
-.011939,.008695,
-.012,.008,
0.0*
%
%ADD31MACRO31*%
%AMMACRO62*
4,1,40,.008,.012,
-.008,.012,
-.008695,.011939,
-.009368,.011759,
-.01,.011464,
-.010571,.011064,
-.011064,.010571,
-.011464,.01,
-.011759,.009368,
-.011939,.008695,
-.012,.008,
-.012,-.008,
-.011939,-.008695,
-.011759,-.009368,
-.011464,-.01,
-.011064,-.010571,
-.010571,-.011064,
-.01,-.011464,
-.009368,-.011759,
-.008695,-.011939,
-.008,-.012,
.008,-.012,
.008695,-.011939,
.009368,-.011759,
.01,-.011464,
.010571,-.011064,
.011064,-.010571,
.011464,-.01,
.011759,-.009368,
.011939,-.008695,
.012,-.008,
.012,.008,
.011939,.008695,
.011759,.009368,
.011464,.01,
.011064,.010571,
.010571,.011064,
.01,.011464,
.009368,.011759,
.008695,.011939,
.008,.012,
0.0*
%
%ADD62MACRO62*%
%AMMACRO77*
4,1,6,.0135,-.025,
-.0065,-.005,
-.0135,-.005,
-.0135,.005,
-.0065,.005,
.0135,.025,
.0135,-.025,
0.0*
%
%ADD77MACRO77*%
%AMMACRO74*
4,1,40,-.013,-.017,
.013,-.017,
.013695,-.016939,
.014368,-.016759,
.015,-.016464,
.015571,-.016064,
.016064,-.015571,
.016464,-.015,
.016759,-.014368,
.016939,-.013695,
.017,-.013,
.017,.013,
.016939,.013695,
.016759,.014368,
.016464,.015,
.016064,.015571,
.015571,.016064,
.015,.016464,
.014368,.016759,
.013695,.016939,
.013,.017,
-.013,.017,
-.013695,.016939,
-.014368,.016759,
-.015,.016464,
-.015571,.016064,
-.016064,.015571,
-.016464,.015,
-.016759,.014368,
-.016939,.013695,
-.017,.013,
-.017,-.013,
-.016939,-.013695,
-.016759,-.014368,
-.016464,-.015,
-.016064,-.015571,
-.015571,-.016064,
-.015,-.016464,
-.014368,-.016759,
-.013695,-.016939,
-.013,-.017,
0.0*
%
%ADD74MACRO74*%
%AMMACRO16*
4,1,40,-.017,.013,
-.017,-.013,
-.016939,-.013695,
-.016759,-.014368,
-.016464,-.015,
-.016064,-.015571,
-.015571,-.016064,
-.015,-.016464,
-.014368,-.016759,
-.013695,-.016939,
-.013,-.017,
.013,-.017,
.013695,-.016939,
.014368,-.016759,
.015,-.016464,
.015571,-.016064,
.016064,-.015571,
.016464,-.015,
.016759,-.014368,
.016939,-.013695,
.017,-.013,
.017,.013,
.016939,.013695,
.016759,.014368,
.016464,.015,
.016064,.015571,
.015571,.016064,
.015,.016464,
.014368,.016759,
.013695,.016939,
.013,.017,
-.013,.017,
-.013695,.016939,
-.014368,.016759,
-.015,.016464,
-.015571,.016064,
-.016064,.015571,
-.016464,.015,
-.016759,.014368,
-.016939,.013695,
-.017,.013,
0.0*
%
%ADD16MACRO16*%
%AMMACRO20*
4,1,6,.005,.0135,
.005,.0065,
.025,-.0135,
-.025,-.0135,
-.005,.0065,
-.005,.0135,
.005,.0135,
0.0*
%
%ADD20MACRO20*%
%AMMACRO30*
4,1,40,.011,-.007,
.011,.007,
.010939,.007695,
.010759,.008368,
.010464,.009,
.010064,.009571,
.009571,.010064,
.009,.010464,
.008368,.010759,
.007695,.010939,
.007,.011,
-.007,.011,
-.007695,.010939,
-.008368,.010759,
-.009,.010464,
-.009571,.010064,
-.010064,.009571,
-.010464,.009,
-.010759,.008368,
-.010939,.007695,
-.011,.007,
-.011,-.007,
-.010939,-.007695,
-.010759,-.008368,
-.010464,-.009,
-.010064,-.009571,
-.009571,-.010064,
-.009,-.010464,
-.008368,-.010759,
-.007695,-.010939,
-.007,-.011,
.007,-.011,
.007695,-.010939,
.008368,-.010759,
.009,-.010464,
.009571,-.010064,
.010064,-.009571,
.010464,-.009,
.010759,-.008368,
.010939,-.007695,
.011,-.007,
0.0*
%
%ADD30MACRO30*%
%AMMACRO25*
4,1,40,.007,.011,
-.007,.011,
-.007695,.010939,
-.008368,.010759,
-.009,.010464,
-.009571,.010064,
-.010064,.009571,
-.010464,.009,
-.010759,.008368,
-.010939,.007695,
-.011,.007,
-.011,-.007,
-.010939,-.007695,
-.010759,-.008368,
-.010464,-.009,
-.010064,-.009571,
-.009571,-.010064,
-.009,-.010464,
-.008368,-.010759,
-.007695,-.010939,
-.007,-.011,
.007,-.011,
.007695,-.010939,
.008368,-.010759,
.009,-.010464,
.009571,-.010064,
.010064,-.009571,
.010464,-.009,
.010759,-.008368,
.010939,-.007695,
.011,-.007,
.011,.007,
.010939,.007695,
.010759,.008368,
.010464,.009,
.010064,.009571,
.009571,.010064,
.009,.010464,
.008368,.010759,
.007695,.010939,
.007,.011,
0.0*
%
%ADD25MACRO25*%
%AMMACRO71*
4,1,20,.0635,-.1075,
.049,-.1075,
.049,-.118,
.0395,-.118,
.0395,-.1075,
-.0395,-.1075,
-.0395,-.118,
-.049,-.118,
-.049,-.1075,
-.0635,-.1075,
-.0635,.1075,
-.049,.1075,
-.049,.118,
-.0395,.118,
-.0395,.1075,
.0395,.1075,
.0395,.118,
.049,.118,
.049,.1075,
.0635,.1075,
.0635,-.1075,
0.0*
%
%ADD71MACRO71*%
%AMMACRO18*
4,1,40,-.012,.008,
-.012,-.008,
-.011939,-.008695,
-.011759,-.009368,
-.011464,-.01,
-.011064,-.010571,
-.010571,-.011064,
-.01,-.011464,
-.009368,-.011759,
-.008695,-.011939,
-.008,-.012,
.008,-.012,
.008695,-.011939,
.009368,-.011759,
.01,-.011464,
.010571,-.011064,
.011064,-.010571,
.011464,-.01,
.011759,-.009368,
.011939,-.008695,
.012,-.008,
.012,.008,
.011939,.008695,
.011759,.009368,
.011464,.01,
.011064,.010571,
.010571,.011064,
.01,.011464,
.009368,.011759,
.008695,.011939,
.008,.012,
-.008,.012,
-.008695,.011939,
-.009368,.011759,
-.01,.011464,
-.010571,.011064,
-.011064,.010571,
-.011464,.01,
-.011759,.009368,
-.011939,.008695,
-.012,.008,
0.0*
%
%ADD18MACRO18*%
%AMMACRO61*
4,1,40,.008,.012,
-.008,.012,
-.008695,.011939,
-.009368,.011759,
-.01,.011464,
-.010571,.011064,
-.011064,.010571,
-.011464,.01,
-.011759,.009368,
-.011939,.008695,
-.012,.008,
-.012,-.008,
-.011939,-.008695,
-.011759,-.009368,
-.011464,-.01,
-.011064,-.010571,
-.010571,-.011064,
-.01,-.011464,
-.009368,-.011759,
-.008695,-.011939,
-.008,-.012,
.008,-.012,
.008695,-.011939,
.009368,-.011759,
.01,-.011464,
.010571,-.011064,
.011064,-.010571,
.011464,-.01,
.011759,-.009368,
.011939,-.008695,
.012,-.008,
.012,.008,
.011939,.008695,
.011759,.009368,
.011464,.01,
.011064,.010571,
.010571,.011064,
.01,.011464,
.009368,.011759,
.008695,.011939,
.008,.012,
0.0*
%
%ADD61MACRO61*%
%AMMACRO75*
4,1,40,-.013,-.017,
.013,-.017,
.013695,-.016939,
.014368,-.016759,
.015,-.016464,
.015571,-.016064,
.016064,-.015571,
.016464,-.015,
.016759,-.014368,
.016939,-.013695,
.017,-.013,
.017,.013,
.016939,.013695,
.016759,.014368,
.016464,.015,
.016064,.015571,
.015571,.016064,
.015,.016464,
.014368,.016759,
.013695,.016939,
.013,.017,
-.013,.017,
-.013695,.016939,
-.014368,.016759,
-.015,.016464,
-.015571,.016064,
-.016064,.015571,
-.016464,.015,
-.016759,.014368,
-.016939,.013695,
-.017,.013,
-.017,-.013,
-.016939,-.013695,
-.016759,-.014368,
-.016464,-.015,
-.016064,-.015571,
-.015571,-.016064,
-.015,-.016464,
-.014368,-.016759,
-.013695,-.016939,
-.013,-.017,
0.0*
%
%ADD75MACRO75*%
%AMMACRO17*
4,1,40,-.017,.013,
-.017,-.013,
-.016939,-.013695,
-.016759,-.014368,
-.016464,-.015,
-.016064,-.015571,
-.015571,-.016064,
-.015,-.016464,
-.014368,-.016759,
-.013695,-.016939,
-.013,-.017,
.013,-.017,
.013695,-.016939,
.014368,-.016759,
.015,-.016464,
.015571,-.016064,
.016064,-.015571,
.016464,-.015,
.016759,-.014368,
.016939,-.013695,
.017,-.013,
.017,.013,
.016939,.013695,
.016759,.014368,
.016464,.015,
.016064,.015571,
.015571,.016064,
.015,.016464,
.014368,.016759,
.013695,.016939,
.013,.017,
-.013,.017,
-.013695,.016939,
-.014368,.016759,
-.015,.016464,
-.015571,.016064,
-.016064,.015571,
-.016464,.015,
-.016759,.014368,
-.016939,.013695,
-.017,.013,
0.0*
%
%ADD17MACRO17*%
%ADD80R,.06X.012*%
%ADD84R,.023X.04*%
%ADD81R,.06X.014*%
%ADD72R,.044X.012*%
%ADD55R,.04X.016*%
%ADD65R,.016X.04*%
%ADD63R,.014X.06*%
%ADD35R,.012X.044*%
%ADD26R,.045X.03*%
%ADD51R,.133X.128*%
%ADD64R,.128X.133*%
%ADD47R,.075X.02*%
%ADD82R,.05X.065*%
%ADD48R,.036X.024*%
%ADD39R,.065X.05*%
%ADD50R,.065X.025*%
%ADD12C,.315*%
%ADD68R,.025X.065*%
%ADD67R,.045X.055*%
%ADD56R,.048X.016*%
%ADD85C,.146*%
%ADD54R,.016X.048*%
%ADD37R,.055X.045*%
%ADD59R,.045X.075*%
%ADD53R,.054X.074*%
%ADD46R,.094X.026*%
%ADD79R,.075X.045*%
%ADD52R,.09X.095*%
%ADD10R,.16X.16*%
%AMMACRO78*
4,1,40,-.0225,.007,
-.022378,.008389,
-.022018,.009736,
-.021428,.011,
-.020628,.012142,
-.019642,.013128,
-.0185,.013928,
-.017236,.014518,
-.015889,.014878,
-.0145,.015,
.0145,.015,
.015889,.014878,
.017236,.014518,
.0185,.013928,
.019642,.013128,
.020628,.012142,
.021428,.011,
.022018,.009736,
.022378,.008389,
.0225,.007,
.0225,-.007,
.022378,-.008389,
.022018,-.009736,
.021428,-.011,
.020628,-.012142,
.019642,-.013128,
.0185,-.013928,
.017236,-.014518,
.015889,-.014878,
.0145,-.015,
-.0145,-.015,
-.015889,-.014878,
-.017236,-.014518,
-.0185,-.013928,
-.019642,-.013128,
-.020628,-.012142,
-.021428,-.011,
-.022018,-.009736,
-.022378,-.008389,
-.0225,-.007,
-.0225,.007,
0.0*
%
%ADD78MACRO78*%
%AMMACRO73*
4,1,40,.007,.0225,
.008389,.022378,
.009736,.022018,
.011,.021428,
.012142,.020628,
.013128,.019642,
.013928,.0185,
.014518,.017236,
.014878,.015889,
.015,.0145,
.015,-.0145,
.014878,-.015889,
.014518,-.017236,
.013928,-.0185,
.013128,-.019642,
.012142,-.020628,
.011,-.021428,
.009736,-.022018,
.008389,-.022378,
.007,-.0225,
-.007,-.0225,
-.008389,-.022378,
-.009736,-.022018,
-.011,-.021428,
-.012142,-.020628,
-.013128,-.019642,
-.013928,-.0185,
-.014518,-.017236,
-.014878,-.015889,
-.015,-.0145,
-.015,.0145,
-.014878,.015889,
-.014518,.017236,
-.013928,.0185,
-.013128,.019642,
-.012142,.020628,
-.011,.021428,
-.009736,.022018,
-.008389,.022378,
-.007,.0225,
.007,.0225,
0.0*
%
%ADD73MACRO73*%
%ADD49R,.095X.09*%
%ADD83R,.089X.059*%
%AMMACRO41*
4,1,40,-.008,-.012,
.008,-.012,
.008695,-.011939,
.009368,-.011759,
.01,-.011464,
.010571,-.011064,
.011064,-.010571,
.011464,-.01,
.011759,-.009368,
.011939,-.008695,
.012,-.008,
.012,.008,
.011939,.008695,
.011759,.009368,
.011464,.01,
.011064,.010571,
.010571,.011064,
.01,.011464,
.009368,.011759,
.008695,.011939,
.008,.012,
-.008,.012,
-.008695,.011939,
-.009368,.011759,
-.01,.011464,
-.010571,.011064,
-.011064,.010571,
-.011464,.01,
-.011759,.009368,
-.011939,.008695,
-.012,.008,
-.012,-.008,
-.011939,-.008695,
-.011759,-.009368,
-.011464,-.01,
-.011064,-.010571,
-.010571,-.011064,
-.01,-.011464,
-.009368,-.011759,
-.008695,-.011939,
-.008,-.012,
0.0*
%
%ADD41MACRO41*%
%AMMACRO33*
4,1,40,.012,-.008,
.012,.008,
.011939,.008695,
.011759,.009368,
.011464,.01,
.011064,.010571,
.010571,.011064,
.01,.011464,
.009368,.011759,
.008695,.011939,
.008,.012,
-.008,.012,
-.008695,.011939,
-.009368,.011759,
-.01,.011464,
-.010571,.011064,
-.011064,.010571,
-.011464,.01,
-.011759,.009368,
-.011939,.008695,
-.012,.008,
-.012,-.008,
-.011939,-.008695,
-.011759,-.009368,
-.011464,-.01,
-.011064,-.010571,
-.010571,-.011064,
-.01,-.011464,
-.009368,-.011759,
-.008695,-.011939,
-.008,-.012,
.008,-.012,
.008695,-.011939,
.009368,-.011759,
.01,-.011464,
.010571,-.011064,
.011064,-.010571,
.011464,-.01,
.011759,-.009368,
.011939,-.008695,
.012,-.008,
0.0*
%
%ADD33MACRO33*%
%AMMACRO23*
4,1,40,-.007,-.011,
.007,-.011,
.007695,-.010939,
.008368,-.010759,
.009,-.010464,
.009571,-.010064,
.010064,-.009571,
.010464,-.009,
.010759,-.008368,
.010939,-.007695,
.011,-.007,
.011,.007,
.010939,.007695,
.010759,.008368,
.010464,.009,
.010064,.009571,
.009571,.010064,
.009,.010464,
.008368,.010759,
.007695,.010939,
.007,.011,
-.007,.011,
-.007695,.010939,
-.008368,.010759,
-.009,.010464,
-.009571,.010064,
-.010064,.009571,
-.010464,.009,
-.010759,.008368,
-.010939,.007695,
-.011,.007,
-.011,-.007,
-.010939,-.007695,
-.010759,-.008368,
-.010464,-.009,
-.010064,-.009571,
-.009571,-.010064,
-.009,-.010464,
-.008368,-.010759,
-.007695,-.010939,
-.007,-.011,
0.0*
%
%ADD23MACRO23*%
%AMMACRO27*
4,1,40,-.011,.007,
-.011,-.007,
-.010939,-.007695,
-.010759,-.008368,
-.010464,-.009,
-.010064,-.009571,
-.009571,-.010064,
-.009,-.010464,
-.008368,-.010759,
-.007695,-.010939,
-.007,-.011,
.007,-.011,
.007695,-.010939,
.008368,-.010759,
.009,-.010464,
.009571,-.010064,
.010064,-.009571,
.010464,-.009,
.010759,-.008368,
.010939,-.007695,
.011,-.007,
.011,.007,
.010939,.007695,
.010759,.008368,
.010464,.009,
.010064,.009571,
.009571,.010064,
.009,.010464,
.008368,.010759,
.007695,.010939,
.007,.011,
-.007,.011,
-.007695,.010939,
-.008368,.010759,
-.009,.010464,
-.009571,.010064,
-.010064,.009571,
-.010464,.009,
-.010759,.008368,
-.010939,.007695,
-.011,.007,
0.0*
%
%ADD27MACRO27*%
%AMMACRO69*
4,1,40,.013,.017,
-.013,.017,
-.013695,.016939,
-.014368,.016759,
-.015,.016464,
-.015571,.016064,
-.016064,.015571,
-.016464,.015,
-.016759,.014368,
-.016939,.013695,
-.017,.013,
-.017,-.013,
-.016939,-.013695,
-.016759,-.014368,
-.016464,-.015,
-.016064,-.015571,
-.015571,-.016064,
-.015,-.016464,
-.014368,-.016759,
-.013695,-.016939,
-.013,-.017,
.013,-.017,
.013695,-.016939,
.014368,-.016759,
.015,-.016464,
.015571,-.016064,
.016064,-.015571,
.016464,-.015,
.016759,-.014368,
.016939,-.013695,
.017,-.013,
.017,.013,
.016939,.013695,
.016759,.014368,
.016464,.015,
.016064,.015571,
.015571,.016064,
.015,.016464,
.014368,.016759,
.013695,.016939,
.013,.017,
0.0*
%
%ADD69MACRO69*%
%AMMACRO42*
4,1,40,.017,-.013,
.017,.013,
.016939,.013695,
.016759,.014368,
.016464,.015,
.016064,.015571,
.015571,.016064,
.015,.016464,
.014368,.016759,
.013695,.016939,
.013,.017,
-.013,.017,
-.013695,.016939,
-.014368,.016759,
-.015,.016464,
-.015571,.016064,
-.016064,.015571,
-.016464,.015,
-.016759,.014368,
-.016939,.013695,
-.017,.013,
-.017,-.013,
-.016939,-.013695,
-.016759,-.014368,
-.016464,-.015,
-.016064,-.015571,
-.015571,-.016064,
-.015,-.016464,
-.014368,-.016759,
-.013695,-.016939,
-.013,-.017,
.013,-.017,
.013695,-.016939,
.014368,-.016759,
.015,-.016464,
.015571,-.016064,
.016064,-.015571,
.016464,-.015,
.016759,-.014368,
.016939,-.013695,
.017,-.013,
0.0*
%
%ADD42MACRO42*%
%AMMACRO21*
4,1,6,.025,.0135,
.005,-.0065,
.005,-.0135,
-.005,-.0135,
-.005,-.0065,
-.025,.0135,
.025,.0135,
0.0*
%
%ADD21MACRO21*%
%AMMACRO76*
4,1,6,.0135,-.005,
.0065,-.005,
-.0135,-.025,
-.0135,.025,
.0065,.005,
.0135,.005,
.0135,-.005,
0.0*
%
%ADD76MACRO76*%
%AMMACRO34*
4,1,20,.1075,.0635,
.1075,.049,
.118,.049,
.118,.0395,
.1075,.0395,
.1075,-.0395,
.118,-.0395,
.118,-.049,
.1075,-.049,
.1075,-.0635,
-.1075,-.0635,
-.1075,-.049,
-.118,-.049,
-.118,-.0395,
-.1075,-.0395,
-.1075,.0395,
-.118,.0395,
-.118,.049,
-.1075,.049,
-.1075,.0635,
.1075,.0635,
0.0*
%
%ADD34MACRO34*%
%AMMACRO40*
4,1,40,-.008,-.012,
.008,-.012,
.008695,-.011939,
.009368,-.011759,
.01,-.011464,
.010571,-.011064,
.011064,-.010571,
.011464,-.01,
.011759,-.009368,
.011939,-.008695,
.012,-.008,
.012,.008,
.011939,.008695,
.011759,.009368,
.011464,.01,
.011064,.010571,
.010571,.011064,
.01,.011464,
.009368,.011759,
.008695,.011939,
.008,.012,
-.008,.012,
-.008695,.011939,
-.009368,.011759,
-.01,.011464,
-.010571,.011064,
-.011064,.010571,
-.011464,.01,
-.011759,.009368,
-.011939,.008695,
-.012,.008,
-.012,-.008,
-.011939,-.008695,
-.011759,-.009368,
-.011464,-.01,
-.011064,-.010571,
-.010571,-.011064,
-.01,-.011464,
-.009368,-.011759,
-.008695,-.011939,
-.008,-.012,
0.0*
%
%ADD40MACRO40*%
%AMMACRO32*
4,1,40,.012,-.008,
.012,.008,
.011939,.008695,
.011759,.009368,
.011464,.01,
.011064,.010571,
.010571,.011064,
.01,.011464,
.009368,.011759,
.008695,.011939,
.008,.012,
-.008,.012,
-.008695,.011939,
-.009368,.011759,
-.01,.011464,
-.010571,.011064,
-.011064,.010571,
-.011464,.01,
-.011759,.009368,
-.011939,.008695,
-.012,.008,
-.012,-.008,
-.011939,-.008695,
-.011759,-.009368,
-.011464,-.01,
-.011064,-.010571,
-.010571,-.011064,
-.01,-.011464,
-.009368,-.011759,
-.008695,-.011939,
-.008,-.012,
.008,-.012,
.008695,-.011939,
.009368,-.011759,
.01,-.011464,
.010571,-.011064,
.011064,-.010571,
.011464,-.01,
.011759,-.009368,
.011939,-.008695,
.012,-.008,
0.0*
%
%ADD32MACRO32*%
%AMMACRO15*
4,1,40,-.007,-.011,
.007,-.011,
.007695,-.010939,
.008368,-.010759,
.009,-.010464,
.009571,-.010064,
.010064,-.009571,
.010464,-.009,
.010759,-.008368,
.010939,-.007695,
.011,-.007,
.011,.007,
.010939,.007695,
.010759,.008368,
.010464,.009,
.010064,.009571,
.009571,.010064,
.009,.010464,
.008368,.010759,
.007695,.010939,
.007,.011,
-.007,.011,
-.007695,.010939,
-.008368,.010759,
-.009,.010464,
-.009571,.010064,
-.010064,.009571,
-.010464,.009,
-.010759,.008368,
-.010939,.007695,
-.011,.007,
-.011,-.007,
-.010939,-.007695,
-.010759,-.008368,
-.010464,-.009,
-.010064,-.009571,
-.009571,-.010064,
-.009,-.010464,
-.008368,-.010759,
-.007695,-.010939,
-.007,-.011,
0.0*
%
%ADD15MACRO15*%
%AMMACRO28*
4,1,40,-.011,.007,
-.011,-.007,
-.010939,-.007695,
-.010759,-.008368,
-.010464,-.009,
-.010064,-.009571,
-.009571,-.010064,
-.009,-.010464,
-.008368,-.010759,
-.007695,-.010939,
-.007,-.011,
.007,-.011,
.007695,-.010939,
.008368,-.010759,
.009,-.010464,
.009571,-.010064,
.010064,-.009571,
.010464,-.009,
.010759,-.008368,
.010939,-.007695,
.011,-.007,
.011,.007,
.010939,.007695,
.010759,.008368,
.010464,.009,
.010064,.009571,
.009571,.010064,
.009,.010464,
.008368,.010759,
.007695,.010939,
.007,.011,
-.007,.011,
-.007695,.010939,
-.008368,.010759,
-.009,.010464,
-.009571,.010064,
-.010064,.009571,
-.010464,.009,
-.010759,.008368,
-.010939,.007695,
-.011,.007,
0.0*
%
%ADD28MACRO28*%
%ADD87C,.02*%
%ADD88C,.006*%
G75*
%LPD*%
G75*
G36*
G01X1017308Y1433722D02*
X991708D01*
Y1451397D01*
X1017308D01*
Y1433722D01*
G37*
G36*
G01X991708Y1453247D02*
X1017308D01*
Y1470922D01*
X991708D01*
Y1453247D01*
G37*
G36*
G01X1017308Y1473722D02*
X991708D01*
Y1491397D01*
X1017308D01*
Y1473722D01*
G37*
G36*
G01X991708Y1493247D02*
X1017308D01*
Y1510922D01*
X991708D01*
Y1493247D01*
G37*
G36*
G01X1017308Y1513722D02*
X991708D01*
Y1531397D01*
X1017308D01*
Y1513722D01*
G37*
G36*
G01Y1553722D02*
X991708D01*
Y1571397D01*
X1017308D01*
Y1553722D01*
G37*
G36*
G01X991708Y1533247D02*
X1017308D01*
Y1550922D01*
X991708D01*
Y1533247D01*
G37*
G36*
G01Y1573247D02*
X1017308D01*
Y1590922D01*
X991708D01*
Y1573247D01*
G37*
G36*
G01X1017307Y1593722D02*
Y1610922D01*
X991708D01*
Y1593722D01*
X1017307D01*
G37*
G54D10*
X-38666Y47522D03*
X-37468Y1947630D03*
X21499Y17050D03*
X1010999Y18550D03*
X1008999Y1968550D03*
X1073242Y50048D03*
G54D20*
X20799Y1973700D03*
X946999Y116300D03*
G54D11*
X-38436Y23633D03*
X-36811Y1104775D03*
X-35919Y1969497D03*
X1072493Y21507D03*
X1075940Y1769358D03*
G54D21*
X20799Y1976200D03*
X946999Y118800D03*
G54D12*
X29531Y309549D03*
Y1029510D03*
X17720Y1903132D03*
X129921Y17716D03*
X271657Y267699D03*
Y673210D03*
Y1078722D03*
Y1484234D03*
Y1889746D03*
X994098Y149588D03*
Y673210D03*
Y1068880D03*
X994093Y1889751D03*
G54D30*
X30499Y1588660D03*
X31999Y1918850D03*
X23999Y1964850D03*
X27999D03*
X46800Y408900D03*
X42900Y601400D03*
X103999Y1468600D03*
X119499Y1106350D03*
X109499Y1198413D03*
X105499D03*
X106999Y1223913D03*
X111999D03*
X111499Y1468600D03*
X115599Y1468550D03*
X141499Y440413D03*
X146499D03*
X136000Y528800D03*
X135999Y1703350D03*
X131999D03*
X159199Y517150D03*
X167199D03*
X166499Y808913D03*
X167499Y833413D03*
X152600Y1681200D03*
X174999Y71350D03*
X185499Y117350D03*
X174199Y517150D03*
X170499Y808913D03*
X172499Y833413D03*
X184600Y1373100D03*
X180500D03*
X201499Y97850D03*
X209499D03*
X192800Y1651100D03*
X217499Y97850D03*
X223436Y1893665D03*
X644049Y1803934D03*
Y1792934D03*
X708549Y1808634D03*
X710549Y1797934D03*
X754978Y335724D03*
X753196Y735182D03*
X755499Y1140350D03*
X756327Y1543096D03*
X753314Y1948513D03*
X816499Y159350D03*
X814999Y1780350D03*
X823999Y159350D03*
X831499D03*
X826100Y666700D03*
X833499Y1780350D03*
X824499D03*
X828000Y1881300D03*
X900499Y84850D03*
X903499Y128350D03*
X924499Y108350D03*
X916499D03*
X932499D03*
X944499D03*
X940499D03*
X952499D03*
G54D40*
X43999Y1964750D03*
X103499Y1297813D03*
X104999Y1702063D03*
X123999Y1734813D03*
X138999Y517313D03*
X142667Y1306460D03*
X132999Y1306813D03*
X137504Y1735523D03*
X161999Y915813D03*
X182499Y71250D03*
X194500Y499200D03*
X215900Y896900D03*
X292999Y86313D03*
X295500Y329200D03*
X298000Y735700D03*
X297000Y1549800D03*
X296858Y1944028D03*
X369300Y72300D03*
X389500Y72200D03*
X693549Y1813334D03*
X870201Y1709850D03*
X907999Y84750D03*
G54D31*
X39799Y1918050D03*
X21799Y1956050D03*
X103345Y931489D03*
Y927989D03*
X104128Y1336952D03*
Y1333452D03*
X108799Y129550D03*
Y126050D03*
Y145050D03*
Y141550D03*
X104745Y525988D03*
Y522488D03*
X108745Y550988D03*
Y547488D03*
X108345Y956489D03*
Y952989D03*
X107628Y1361952D03*
Y1358452D03*
X105299Y1743050D03*
Y1739550D03*
X107299Y1764050D03*
Y1767550D03*
X132750Y1081100D03*
Y1077600D03*
X183299Y99050D03*
X181999Y524850D03*
X701349Y1813134D03*
X839299Y167550D03*
X839799Y1788050D03*
X907299Y124550D03*
X954799Y96050D03*
G54D13*
X9843Y353144D03*
Y717711D03*
Y762617D03*
Y875216D03*
Y1337396D03*
Y1701963D03*
Y1746869D03*
Y1859468D03*
G54D22*
X38999Y372160D03*
X29999Y849660D03*
X20499Y1315050D03*
X34999Y1572550D03*
X35900Y1832700D03*
X26499Y1935550D03*
X26999Y1941550D03*
X57400Y610900D03*
X102999Y29050D03*
X100999Y468550D03*
X96999Y1632050D03*
X109999Y872550D03*
X107699Y1510950D03*
X118999Y1525550D03*
X126999Y1119050D03*
X141499Y1267050D03*
X162500Y557500D03*
X202999Y90550D03*
X197226Y90428D03*
X233100Y1929800D03*
X287999Y315550D03*
X288999Y723550D03*
X655049Y1810634D03*
X807499Y1089550D03*
X803499Y1496050D03*
X814499Y1809050D03*
X806499Y1903550D03*
X824499Y205050D03*
X843700Y312200D03*
X841500Y713000D03*
X920999Y103050D03*
X914999D03*
G54D32*
X39799Y1921550D03*
X57299Y1901550D03*
X88300Y1097500D03*
Y1111500D03*
X109250Y1348100D03*
Y1344600D03*
X131799Y224550D03*
Y228050D03*
Y249050D03*
Y252550D03*
X127300Y433600D03*
X135238Y630065D03*
Y633565D03*
Y654565D03*
Y658065D03*
X132799Y1035550D03*
Y1039050D03*
Y1060050D03*
Y1063550D03*
X131190Y1441241D03*
Y1444741D03*
Y1465741D03*
Y1469241D03*
X131892Y1846254D03*
Y1849754D03*
Y1870754D03*
Y1874254D03*
X859278Y224924D03*
Y228424D03*
Y249424D03*
Y252924D03*
X859496Y630382D03*
Y633882D03*
Y654882D03*
Y658382D03*
X859133Y1035892D03*
Y1039392D03*
Y1060892D03*
Y1064392D03*
X860627Y1440796D03*
Y1444296D03*
Y1465796D03*
Y1469296D03*
X862614Y1846613D03*
Y1850113D03*
Y1871113D03*
Y1874613D03*
G54D23*
X35500Y597400D03*
Y593300D03*
X34699Y616050D03*
X38800Y607326D03*
Y603200D03*
X22799Y1065050D03*
X21699Y1936050D03*
Y1944050D03*
X51799Y217100D03*
X43100Y597400D03*
X48400Y635500D03*
Y639600D03*
X60449Y656487D03*
Y652487D03*
Y648487D03*
X41699Y1838050D03*
Y1842050D03*
X79199Y642550D03*
X82700Y1013000D03*
X67299Y1851900D03*
X87299Y1000450D03*
Y1004450D03*
X101299Y1081700D03*
Y1077400D03*
X92700Y1553500D03*
Y1557500D03*
X122199Y1125050D03*
X123699Y1343050D03*
X123199Y1356050D03*
Y1352050D03*
X118949Y1476050D03*
X109199Y1716613D03*
Y1720613D03*
X137699Y423113D03*
Y427113D03*
X139600Y1210400D03*
X128000Y1319900D03*
X131700Y1365000D03*
X158199Y165050D03*
Y161050D03*
X157499Y540050D03*
Y544250D03*
X157699Y570050D03*
Y566050D03*
X158199Y975550D03*
Y971550D03*
X147699Y1722550D03*
Y1718550D03*
X158171Y1786909D03*
Y1782909D03*
X182826Y82428D03*
X180199Y156550D03*
Y165050D03*
Y161050D03*
X172400Y424400D03*
X180199Y572050D03*
Y568050D03*
Y564050D03*
X174700Y922700D03*
X183800Y931600D03*
X179949Y976550D03*
Y972550D03*
X180199Y967550D03*
X180764Y1786613D03*
Y1782613D03*
Y1778613D03*
X198800Y823000D03*
X194699Y1381050D03*
Y1377050D03*
Y1373050D03*
X198749Y1635113D03*
Y1630613D03*
X229700Y689500D03*
X227950Y1082500D03*
X228200Y1480100D03*
X233699Y101050D03*
Y97050D03*
X232100Y283000D03*
X233100Y1499300D03*
X305700Y90700D03*
X308699Y343550D03*
X310199Y360050D03*
Y356050D03*
Y750050D03*
X311199Y767050D03*
Y762550D03*
X310199Y1573050D03*
X306699Y1562550D03*
X310199Y1577050D03*
X313558Y1953328D03*
X313477Y1966191D03*
Y1962191D03*
X337699Y63050D03*
Y67050D03*
X378699Y53050D03*
Y57050D03*
X386699Y30550D03*
Y26050D03*
X404199Y51050D03*
Y56050D03*
X651749Y1803634D03*
Y1796134D03*
X651249Y1818634D03*
X697249Y1821634D03*
Y1825634D03*
X739749Y1806634D03*
Y1798634D03*
Y1814134D03*
X779100Y336200D03*
X777800Y736700D03*
X777900Y1138200D03*
X780500Y1543100D03*
X777749Y1817634D03*
X779699Y1949050D03*
X789249Y1804634D03*
Y1800634D03*
X817199Y1825550D03*
Y1821550D03*
X849178Y280924D03*
X847896Y681882D03*
X847533Y1087392D03*
X861799Y1372200D03*
X849527Y1492296D03*
X850014Y1898113D03*
X874928Y163924D03*
Y159924D03*
X886699Y570550D03*
Y565050D03*
X886533Y975892D03*
Y971892D03*
X873527Y1379796D03*
Y1375796D03*
X881801Y1720950D03*
X886300Y1786300D03*
X886264Y1782213D03*
X905699Y99050D03*
X889301Y1720950D03*
X925928Y168424D03*
Y164424D03*
X925699Y172550D03*
X908646Y570882D03*
Y566882D03*
Y562882D03*
X908533Y974392D03*
Y970392D03*
Y966392D03*
X908264Y1785613D03*
Y1781613D03*
Y1777613D03*
G54D41*
X43999Y1968350D03*
X103499Y1301413D03*
X104999Y1705663D03*
X123999Y1738413D03*
X138999Y520913D03*
X142667Y1310060D03*
X132999Y1310413D03*
X137504Y1739123D03*
X161999Y919413D03*
X182499Y74850D03*
X194500Y502800D03*
X215900Y900500D03*
X292999Y89913D03*
X295500Y332800D03*
X298000Y739300D03*
X297000Y1553400D03*
X296858Y1947628D03*
X369300Y75900D03*
X389500Y75800D03*
X693549Y1816934D03*
X870201Y1713450D03*
X907999Y88350D03*
G54D50*
X84999Y1121050D03*
Y1126050D03*
Y1131050D03*
Y1136050D03*
X104999Y1131050D03*
Y1126050D03*
Y1121050D03*
Y1136050D03*
X138499Y1216113D03*
Y1221113D03*
Y1226113D03*
Y1231113D03*
X158499Y1216113D03*
Y1231113D03*
Y1226113D03*
Y1221113D03*
X168499Y1625613D03*
Y1630613D03*
Y1635613D03*
Y1640613D03*
X173999Y430050D03*
Y435050D03*
Y440050D03*
Y445050D03*
X188499Y1635613D03*
Y1630613D03*
Y1625613D03*
Y1640613D03*
X193999Y430050D03*
Y445050D03*
Y440050D03*
Y435050D03*
X198499Y828613D03*
Y833613D03*
Y838613D03*
Y843613D03*
X218499Y833613D03*
Y828613D03*
Y843613D03*
Y838613D03*
X253998Y295114D03*
Y300114D03*
Y305114D03*
Y310114D03*
X254499Y701550D03*
Y706550D03*
Y711550D03*
Y716550D03*
X252999Y1513050D03*
Y1518050D03*
Y1523050D03*
Y1528050D03*
X273998Y305114D03*
Y300114D03*
Y295114D03*
Y310114D03*
X274499Y706550D03*
Y701550D03*
Y716550D03*
Y711550D03*
X272999Y1528050D03*
Y1523050D03*
Y1518050D03*
Y1513050D03*
X255777Y1917191D03*
Y1922191D03*
Y1927191D03*
Y1932191D03*
X279999Y351050D03*
Y356050D03*
Y361050D03*
Y366050D03*
X280999Y757550D03*
Y762550D03*
Y767550D03*
Y772550D03*
X279999Y1568550D03*
Y1573550D03*
Y1578550D03*
Y1583550D03*
X275777Y1932191D03*
Y1927191D03*
Y1922191D03*
Y1917191D03*
X279777Y1961191D03*
Y1966191D03*
Y1971191D03*
Y1976191D03*
X299999Y366050D03*
Y361050D03*
Y356050D03*
Y351050D03*
X300999Y767550D03*
Y762550D03*
Y757550D03*
Y772550D03*
X299999Y1573550D03*
Y1568550D03*
Y1583550D03*
Y1578550D03*
X299777Y1976191D03*
Y1971191D03*
Y1966191D03*
Y1961191D03*
X356499Y21550D03*
Y26550D03*
Y31550D03*
Y36550D03*
X376499Y31550D03*
Y26550D03*
Y21550D03*
Y36550D03*
X777978Y341924D03*
Y346924D03*
Y351924D03*
Y356924D03*
X776696Y742382D03*
Y747382D03*
Y752382D03*
Y757382D03*
X776833Y1143892D03*
Y1148892D03*
Y1153892D03*
Y1158892D03*
X779327Y1548796D03*
Y1553796D03*
Y1558796D03*
Y1563796D03*
X776814Y1954713D03*
Y1959713D03*
Y1964713D03*
Y1969713D03*
X802873Y292471D03*
Y297471D03*
Y302471D03*
Y307471D03*
X797978Y346924D03*
Y341924D03*
Y356924D03*
Y351924D03*
X800831Y696853D03*
Y701853D03*
Y706853D03*
Y711853D03*
X796696Y747382D03*
Y742382D03*
Y757382D03*
Y752382D03*
X800841Y1101216D03*
Y1106216D03*
Y1111216D03*
Y1116216D03*
X796833Y1148892D03*
Y1143892D03*
Y1158892D03*
Y1153892D03*
X802245Y1503722D03*
Y1508722D03*
Y1513722D03*
Y1518722D03*
X799327Y1553796D03*
Y1548796D03*
Y1563796D03*
Y1558796D03*
X801436Y1910365D03*
Y1915365D03*
Y1920365D03*
Y1925365D03*
X796814Y1954713D03*
Y1969713D03*
Y1964713D03*
Y1959713D03*
X822873Y302471D03*
Y297471D03*
Y292471D03*
Y307471D03*
X820831Y706853D03*
Y701853D03*
Y696853D03*
Y711853D03*
X820841Y1106216D03*
Y1101216D03*
Y1116216D03*
Y1111216D03*
X822245Y1508722D03*
Y1503722D03*
Y1518722D03*
Y1513722D03*
X821436Y1910365D03*
Y1925365D03*
Y1920365D03*
Y1915365D03*
G54D14*
X12569Y372041D03*
Y375978D03*
Y379915D03*
Y383852D03*
Y387789D03*
Y391726D03*
Y395663D03*
Y399600D03*
Y403537D03*
Y407474D03*
Y411411D03*
Y431098D03*
Y427161D03*
Y423223D03*
Y435035D03*
Y438972D03*
Y442909D03*
Y446846D03*
Y450783D03*
Y454720D03*
Y458657D03*
Y462594D03*
Y466531D03*
Y470468D03*
Y474405D03*
Y478342D03*
Y482279D03*
Y486216D03*
Y490153D03*
Y494090D03*
Y498027D03*
Y501964D03*
Y505901D03*
Y509838D03*
Y513775D03*
Y517712D03*
Y521649D03*
Y525586D03*
Y529523D03*
Y533460D03*
Y537397D03*
Y541334D03*
Y545271D03*
Y549208D03*
Y553145D03*
Y557082D03*
Y561019D03*
Y564956D03*
Y568893D03*
Y572830D03*
Y576767D03*
Y580704D03*
Y584641D03*
Y588578D03*
Y592515D03*
Y596452D03*
Y600389D03*
Y604326D03*
Y608263D03*
Y612200D03*
Y616137D03*
Y620074D03*
Y624011D03*
Y627948D03*
Y631885D03*
Y635822D03*
Y639759D03*
Y643696D03*
Y647633D03*
Y651570D03*
Y655507D03*
Y659444D03*
Y663381D03*
Y671255D03*
Y667318D03*
Y675192D03*
Y679129D03*
Y683066D03*
Y687003D03*
Y690940D03*
Y694877D03*
Y698814D03*
X12560Y793325D03*
Y789388D03*
Y785451D03*
Y781514D03*
Y813010D03*
Y809073D03*
Y805136D03*
Y801199D03*
Y797262D03*
Y832696D03*
Y820884D03*
Y816947D03*
Y856318D03*
Y852381D03*
Y848444D03*
Y844507D03*
Y840570D03*
Y836633D03*
X12569Y1356293D03*
Y1360230D03*
Y1364167D03*
Y1368104D03*
Y1372041D03*
Y1375978D03*
Y1379915D03*
Y1383852D03*
Y1387789D03*
Y1391726D03*
Y1395663D03*
Y1415350D03*
Y1411413D03*
Y1407475D03*
Y1419287D03*
Y1423224D03*
Y1427161D03*
Y1431098D03*
Y1435035D03*
Y1438972D03*
Y1442909D03*
Y1446846D03*
Y1450783D03*
Y1454720D03*
Y1458657D03*
Y1462594D03*
Y1466531D03*
Y1470468D03*
Y1474405D03*
Y1478342D03*
Y1482279D03*
Y1486216D03*
Y1490153D03*
Y1494090D03*
Y1498027D03*
Y1501964D03*
Y1505901D03*
Y1509838D03*
Y1513775D03*
Y1517712D03*
Y1521649D03*
Y1525586D03*
Y1529523D03*
Y1533460D03*
Y1537397D03*
Y1541334D03*
Y1545271D03*
Y1549208D03*
Y1553145D03*
Y1557082D03*
Y1561019D03*
Y1564956D03*
Y1568893D03*
Y1572830D03*
Y1576767D03*
Y1580704D03*
Y1584641D03*
Y1588578D03*
Y1592515D03*
Y1596452D03*
Y1600389D03*
Y1604326D03*
Y1608263D03*
Y1612200D03*
Y1616137D03*
Y1620074D03*
Y1624011D03*
Y1627948D03*
Y1631885D03*
Y1635822D03*
Y1639759D03*
Y1643696D03*
Y1655507D03*
Y1651570D03*
Y1647633D03*
Y1659444D03*
Y1663381D03*
Y1667318D03*
Y1675192D03*
Y1671255D03*
Y1679129D03*
Y1683066D03*
X12560Y1765766D03*
Y1785451D03*
Y1781514D03*
Y1777577D03*
Y1773640D03*
Y1769703D03*
Y1805136D03*
Y1801199D03*
Y1797262D03*
Y1793325D03*
Y1789388D03*
Y1828759D03*
Y1824822D03*
Y1820885D03*
Y1816948D03*
Y1840570D03*
Y1836633D03*
Y1832696D03*
G54D15*
X19399Y1065050D03*
X18299Y1936050D03*
Y1944050D03*
X32100Y597400D03*
Y593300D03*
X39700Y597400D03*
X31299Y616050D03*
X35400Y607326D03*
Y603200D03*
X38299Y1838050D03*
Y1842050D03*
X48399Y217100D03*
X45000Y635500D03*
Y639600D03*
X57049Y656487D03*
Y652487D03*
Y648487D03*
X75799Y642550D03*
X79300Y1013000D03*
X63899Y1851900D03*
X83899Y1000450D03*
Y1004450D03*
X97899Y1081700D03*
Y1077400D03*
X89300Y1553500D03*
Y1557500D03*
X118799Y1125050D03*
X124600Y1319900D03*
X120299Y1343050D03*
X119799Y1356050D03*
Y1352050D03*
X115549Y1476050D03*
X105799Y1716613D03*
Y1720613D03*
X134299Y423113D03*
Y427113D03*
X136200Y1210400D03*
X128300Y1365000D03*
X144299Y1722550D03*
Y1718550D03*
X154799Y165050D03*
Y161050D03*
X154099Y540050D03*
Y544250D03*
X154299Y570050D03*
Y566050D03*
X154799Y975550D03*
Y971550D03*
X154771Y1786909D03*
Y1782909D03*
X179426Y82428D03*
X176799Y156550D03*
Y165050D03*
Y161050D03*
X169000Y424400D03*
X176799Y572050D03*
Y568050D03*
Y564050D03*
X171300Y922700D03*
X180400Y931600D03*
X176549Y976550D03*
Y972550D03*
X176799Y967550D03*
X177364Y1786613D03*
Y1782613D03*
Y1778613D03*
X195400Y823000D03*
X191299Y1381050D03*
Y1377050D03*
Y1373050D03*
X195349Y1635113D03*
Y1630613D03*
X230299Y101050D03*
Y97050D03*
X228700Y283000D03*
X226300Y689500D03*
X224550Y1082500D03*
X224800Y1480100D03*
X229700Y1499300D03*
X302300Y90700D03*
X305299Y343550D03*
X306799Y360050D03*
Y356050D03*
Y750050D03*
X307799Y767050D03*
Y762550D03*
X306799Y1573050D03*
X303299Y1562550D03*
X306799Y1577050D03*
X310158Y1953328D03*
X310077Y1966191D03*
Y1962191D03*
X334299Y63050D03*
Y67050D03*
X375299Y53050D03*
Y57050D03*
X383299Y30550D03*
Y26050D03*
X400799Y51050D03*
Y56050D03*
X648349Y1803634D03*
Y1796134D03*
X647849Y1818634D03*
X693849Y1821634D03*
Y1825634D03*
X736349Y1806634D03*
Y1798634D03*
Y1814134D03*
X775700Y336200D03*
X774400Y736700D03*
X774500Y1138200D03*
X777100Y1543100D03*
X774349Y1817634D03*
X776299Y1949050D03*
X785849Y1804634D03*
Y1800634D03*
X813799Y1825550D03*
Y1821550D03*
X844496Y681882D03*
X844133Y1087392D03*
X845778Y280924D03*
X858399Y1372200D03*
X846127Y1492296D03*
X846614Y1898113D03*
X871528Y163924D03*
Y159924D03*
X883299Y570550D03*
Y565050D03*
X883133Y975892D03*
Y971892D03*
X870127Y1379796D03*
Y1375796D03*
X878401Y1720950D03*
X885901D03*
X882900Y1786300D03*
X882864Y1782213D03*
X902299Y99050D03*
X905246Y570882D03*
Y566882D03*
Y562882D03*
X905133Y974392D03*
Y970392D03*
Y966392D03*
X904864Y1785613D03*
Y1781613D03*
Y1777613D03*
X922528Y168424D03*
Y164424D03*
X922299Y172550D03*
G54D42*
X49999Y1971850D03*
X107999Y1303913D03*
X109499Y1708413D03*
X143499Y523413D03*
X136600Y1180200D03*
X166499Y921913D03*
X218998Y317914D03*
X213598Y350914D03*
X218499Y724850D03*
X214599Y757850D03*
X217600Y1127800D03*
X217999Y1534850D03*
X218814Y1925913D03*
X213600Y1962400D03*
X297499Y92413D03*
X783049Y1819434D03*
X788049D03*
X858999Y311850D03*
X864900Y344900D03*
X855696Y712182D03*
X862896Y746382D03*
X855333Y1117692D03*
X862933Y1149192D03*
X857827Y1522596D03*
X865700Y1552400D03*
X857314Y1928413D03*
X864500Y1962200D03*
G54D33*
X36199Y1921550D03*
X53699Y1901550D03*
X84700Y1097500D03*
Y1111500D03*
X123700Y433600D03*
X105650Y1348100D03*
Y1344600D03*
X128199Y224550D03*
Y228050D03*
Y249050D03*
Y252550D03*
X131638Y630065D03*
Y633565D03*
Y654565D03*
Y658065D03*
X129199Y1035550D03*
Y1039050D03*
Y1060050D03*
Y1063550D03*
X127590Y1441241D03*
Y1444741D03*
Y1465741D03*
Y1469241D03*
X128292Y1846254D03*
Y1849754D03*
Y1870754D03*
Y1874254D03*
X855678Y224924D03*
Y228424D03*
Y249424D03*
Y252924D03*
X855896Y630382D03*
Y633882D03*
Y654882D03*
Y658382D03*
X855533Y1035892D03*
Y1039392D03*
Y1060892D03*
Y1064392D03*
X857027Y1440796D03*
Y1444296D03*
Y1465796D03*
Y1469296D03*
X859014Y1846613D03*
Y1850113D03*
Y1871113D03*
Y1874613D03*
G54D51*
X76038Y1929550D03*
X110960D03*
G54D60*
X125725Y1326750D03*
X145000Y539050D03*
X141125Y531550D03*
X129600Y1334250D03*
X133475Y1326750D03*
X148875Y531550D03*
X157825Y1682050D03*
X165575D03*
X161700Y1689550D03*
X180025Y918250D03*
X187775D03*
X183900Y925750D03*
X307000Y105150D03*
X303125Y97650D03*
X310875D03*
G54D24*
X28586Y600248D03*
X34700Y623000D03*
X39499Y615550D03*
X28519Y605048D03*
X40734Y802473D03*
X22300Y1069100D03*
X38499Y1601050D03*
X39990Y1927445D03*
X33573Y1928650D03*
X26499Y1947050D03*
X36699Y1963300D03*
X26999Y1973550D03*
X28389Y1958362D03*
X52499Y198550D03*
X61757Y216415D03*
X56999Y217050D03*
X41499Y219050D03*
X52730Y406470D03*
X60400Y616000D03*
X55500Y618500D03*
X41367Y639102D03*
X53400Y630500D03*
X43500Y631500D03*
X61999Y661550D03*
X52499Y1013550D03*
X60172Y1566828D03*
X42449Y1588600D03*
X57999Y1830050D03*
X46499Y1850050D03*
X46999Y1832550D03*
X41597Y1912934D03*
X43999Y1924050D03*
X44624Y1974886D03*
X69510Y217221D03*
X77749Y213500D03*
X71800Y622700D03*
X62500Y633300D03*
X66023Y638100D03*
X76499Y637550D03*
X68000Y1028800D03*
X74999Y1126550D03*
X63014Y1560986D03*
X78099Y1827250D03*
X81499Y1847550D03*
X77999Y1832350D03*
X94735Y1110135D03*
X99999Y1202550D03*
X100999Y1213550D03*
X100499Y1226050D03*
X97999Y1486550D03*
X95899Y1475350D03*
X89499Y1843113D03*
X83499Y1841550D03*
X90800Y1832500D03*
X106499Y834550D03*
X124999Y1110550D03*
X121999Y1117050D03*
X114499Y1135050D03*
X115499Y1197550D03*
X117499Y1214050D03*
X123299Y1206900D03*
X105999Y1311050D03*
X116499Y1335050D03*
X112499Y1329050D03*
X115499Y1364550D03*
X113999Y1380550D03*
X123500Y1372000D03*
X120499Y1470550D03*
X121499Y1511050D03*
X108000Y1517000D03*
X121499Y1708050D03*
X109249Y1725800D03*
X144999Y419550D03*
X137500Y444600D03*
X132999Y475550D03*
X135300Y524329D03*
X134899Y538200D03*
X135300Y549500D03*
X125999Y1087550D03*
X126999Y1143550D03*
X127800Y1163400D03*
X140911Y1201878D03*
X135400Y1205700D03*
X143900Y1262600D03*
X146300Y1277900D03*
X129699Y1315605D03*
X136200Y1342600D03*
X135400Y1624100D03*
X143500Y1702900D03*
X144999Y1711050D03*
X166999Y155550D03*
X162177Y154550D03*
X161999Y426450D03*
X156959Y426292D03*
X151699Y524650D03*
X155999Y535775D03*
X167200Y561000D03*
X156499Y548550D03*
X157749Y562000D03*
X166499Y841550D03*
X156969Y917050D03*
X160999Y942550D03*
X158800Y967500D03*
X164999Y965050D03*
Y1305550D03*
X153500Y1326700D03*
X148000Y1346500D03*
X151499Y1673550D03*
X148100Y1683400D03*
X158499Y1729050D03*
X158027Y1778300D03*
X166999Y1774550D03*
X188999Y88550D03*
X187024Y76235D03*
X171499Y153550D03*
X176900Y424600D03*
X168900Y419100D03*
X168500Y472000D03*
X168299Y503150D03*
X179000Y535500D03*
X179499Y542550D03*
X172199Y557108D03*
X177999Y559300D03*
X179999Y826050D03*
X179499Y820550D03*
X171000Y927000D03*
X178999Y961550D03*
X188499Y982050D03*
X171499Y965050D03*
X173499Y1217050D03*
X186000Y1382400D03*
X176999Y1367550D03*
X171499Y1370550D03*
X171999Y1658550D03*
X168999Y1651050D03*
X174800Y1670800D03*
X178900Y1700113D03*
X172999Y1775050D03*
X177314Y1772050D03*
X191499Y74497D03*
X208999Y92050D03*
X200999Y159050D03*
X191449Y152000D03*
X201561Y164541D03*
X207128Y440421D03*
X199499Y545550D03*
X193999Y558050D03*
X200999Y565050D03*
X200417Y569815D03*
X204000Y823000D03*
Y817500D03*
X203000Y918000D03*
X194800Y925500D03*
X193549Y962550D03*
X199999Y971050D03*
X197999Y1359050D03*
X190499Y1367550D03*
X208999Y1366550D03*
X200900Y1657200D03*
X194999Y1640613D03*
X198300Y1649800D03*
X201499Y1784750D03*
X192999Y1771550D03*
X227022Y85278D03*
X229296Y81050D03*
X230811Y88226D03*
X224499Y92050D03*
X225499Y100050D03*
X218499Y183050D03*
X231400Y262800D03*
X221799Y276150D03*
X212578Y287448D03*
X212499Y296050D03*
Y307050D03*
X211999Y327550D03*
X215400Y516400D03*
X213299Y693800D03*
X212499Y701550D03*
X216999Y713050D03*
X212499Y736050D03*
X225499Y941550D03*
X227028Y1071148D03*
X223700Y1078500D03*
X212600Y1089961D03*
X210999Y1100550D03*
X216499Y1377550D03*
X223501Y1487433D03*
X211914Y1504015D03*
X212000Y1512500D03*
X217749Y1522300D03*
X212249Y1544800D03*
X218499Y1897050D03*
X236800Y283500D03*
X239300Y669600D03*
X234500Y690652D03*
X244700Y743100D03*
X247000Y768500D03*
X232300Y834200D03*
X237499Y900050D03*
X244400Y1110200D03*
X233500Y1113100D03*
X250500Y1127500D03*
X250499Y1165550D03*
X242700Y1499400D03*
X240100Y1875000D03*
X245249Y1896283D03*
X265499Y322050D03*
X257000Y316214D03*
X253999Y370050D03*
X258200Y722300D03*
X255999Y1112150D03*
X258800Y1534000D03*
X260500Y1540800D03*
X253399Y1586550D03*
X268499Y1706550D03*
X286499Y43613D03*
X287100Y86363D03*
X283999Y708550D03*
X279499Y1521050D03*
X278999Y1950550D03*
X307300Y113300D03*
X295500Y101900D03*
X305999Y141050D03*
X299000Y340500D03*
X312912Y345936D03*
X314400Y370100D03*
X301099Y750750D03*
X311999Y773550D03*
X301499Y927050D03*
X304499Y1549550D03*
X307749Y1583300D03*
X297499Y1797050D03*
X306199Y1937010D03*
X309999Y1976191D03*
X328500Y71500D03*
X319102Y346300D03*
X322200Y369300D03*
X330249Y750050D03*
X318499Y752050D03*
X324499Y753050D03*
X327000Y772300D03*
X317499Y1549050D03*
X328600Y1566100D03*
X329100Y1582600D03*
X335520Y1953650D03*
X323999Y1938550D03*
X331999Y1957550D03*
X329999Y1962550D03*
X330000Y1971600D03*
X358059Y55550D03*
X343699Y1475950D03*
X370500Y42900D03*
X378700Y47300D03*
X404499Y39300D03*
X402999Y46550D03*
X409999Y54050D03*
X410379Y328650D03*
X459999Y1862050D03*
X478599Y1075450D03*
X503379Y621150D03*
X496379Y1492150D03*
X599499Y79550D03*
X634999Y1803050D03*
X633931Y1795465D03*
X659949Y1803670D03*
X664549Y1797436D03*
X661549Y1822634D03*
X690999Y1295550D03*
X685549Y1799134D03*
X681549Y1825234D03*
X687049Y1822334D03*
X715549Y1799634D03*
X717564Y1804045D03*
X732549Y1802934D03*
X738049Y1793884D03*
X720300Y1808884D03*
X746999Y325550D03*
X752999Y343550D03*
X750099Y333550D03*
X745696Y725050D03*
X746999Y741050D03*
X747499Y733762D03*
X745599Y1129050D03*
X749499Y1142550D03*
X754151Y1135982D03*
X745600Y1531296D03*
X754999Y1550788D03*
X752099Y1540568D03*
X741549Y1818384D03*
X749499Y1933050D03*
X751096Y1955250D03*
X748299Y1946363D03*
X763937Y348257D03*
X775650Y331900D03*
X776999Y690050D03*
X779200Y732800D03*
X774350Y732900D03*
X762898Y1152400D03*
X774200Y1133700D03*
X777050Y1539200D03*
X768379Y1778150D03*
X768549Y1816634D03*
X776100Y1944200D03*
X779900Y1976200D03*
X762700Y1961800D03*
X785999Y285550D03*
X781999Y1085050D03*
X791499Y1492550D03*
X781904Y1538188D03*
X786699Y1808934D03*
X785799Y1795634D03*
X790499Y1899550D03*
X818013Y173064D03*
X817999Y182050D03*
X806499Y364152D03*
X815000Y687500D03*
X822100Y1470700D03*
X819593Y1783807D03*
X817249Y1793050D03*
X823499Y1825050D03*
X815499Y1817050D03*
X822700Y1875100D03*
X809600Y1887560D03*
X840499Y182550D03*
X829999Y200550D03*
X827774Y213183D03*
X836499Y213162D03*
X838299Y204800D03*
X836600Y261000D03*
X830000Y294500D03*
X835300Y663200D03*
X834500Y1067600D03*
X827500Y1102000D03*
X836600Y1471100D03*
X829000Y1505500D03*
X829199Y1783750D03*
X840400Y1827100D03*
X837499Y1876900D03*
X829000Y1913000D03*
X854200Y269500D03*
X847577Y272131D03*
X847200Y267200D03*
X846400Y665500D03*
X847200Y672000D03*
X852703Y667497D03*
X855499Y700550D03*
X860499Y691050D03*
X862700Y735300D03*
X851600Y1073300D03*
X846400Y1078700D03*
X846500Y1073500D03*
X855500Y1106500D03*
X861500Y1095000D03*
X863000Y1139000D03*
X847500Y1367000D03*
X854327Y1481596D03*
X848300Y1483000D03*
X845700Y1477100D03*
X858499Y1511550D03*
X846000Y1811400D03*
X849800Y1888300D03*
X854814Y1887250D03*
X847700Y1881900D03*
X882999Y160434D03*
X885499Y165050D03*
X873999Y484550D03*
X886749Y560500D03*
X876787Y567743D03*
X886583Y967600D03*
X877499Y977050D03*
X869587Y1354050D03*
X880499Y1367550D03*
X882999Y1374550D03*
X879999Y1380170D03*
X871100Y1690300D03*
X886200Y1776200D03*
X905499Y94550D03*
X907499Y160434D03*
X899685Y559592D03*
X894200Y560400D03*
X906999Y557050D03*
X905999Y962050D03*
X894999Y963050D03*
X891999Y1363550D03*
X893000Y1695500D03*
X899500Y1720700D03*
X897239Y1771500D03*
X892999Y1776050D03*
X899599Y1776604D03*
X913999Y58050D03*
X912399Y88150D03*
X910499Y98550D03*
X926499Y103050D03*
X922999Y158550D03*
X916999Y168424D03*
X921999Y557050D03*
X927999Y568550D03*
X922049Y961050D03*
X921499Y1770050D03*
X914999Y1791500D03*
X944499Y95050D03*
X941873Y103050D03*
X935999Y104050D03*
X937499Y158500D03*
X945999Y166550D03*
X929499Y971100D03*
X964042Y96050D03*
X954499Y116550D03*
G54D34*
X44368Y1946712D03*
G54D52*
X91099Y1870050D03*
Y1890550D03*
X124500Y1583500D03*
X115899Y1870050D03*
Y1890550D03*
X149300Y1583500D03*
G54D61*
X122799Y1485350D03*
X159500Y821800D03*
X178999Y74850D03*
X213499Y101350D03*
X216998Y287414D03*
X216999Y693850D03*
X222900Y1090100D03*
X216999Y1503850D03*
X235499Y84850D03*
X232314Y1897413D03*
X312800Y321100D03*
X308999Y728350D03*
X309299Y1536750D03*
X313499Y1931850D03*
X655549Y1796434D03*
Y1803934D03*
X693549Y1801934D03*
Y1809434D03*
X755500Y709800D03*
X759500Y1922800D03*
X764500Y308300D03*
X779978Y308224D03*
X777500Y709800D03*
X760500Y1110800D03*
X778500D03*
X762000Y1516800D03*
X783200Y1516500D03*
X784500Y1922800D03*
X858478Y281224D03*
X857196Y682182D03*
X856833Y1087692D03*
X858827Y1492596D03*
X859314Y1898413D03*
X904499Y88350D03*
X928499Y111850D03*
G54D25*
X34699Y611550D03*
X21699Y1948050D03*
Y1952050D03*
Y1940050D03*
X59199Y203550D03*
Y207550D03*
Y211550D03*
X59699Y1017050D03*
X59636Y1021050D03*
Y1025050D03*
X55699Y1897050D03*
X81199Y204550D03*
Y208550D03*
X81201Y611450D03*
Y615450D03*
X77199Y1837550D03*
X77449Y1843113D03*
X77199Y1849050D03*
X84700Y1008500D03*
X100700Y1115400D03*
X103949Y1476050D03*
X85949Y1828613D03*
Y1832613D03*
X108950Y972000D03*
X108899Y967850D03*
X116199Y1298113D03*
X111449Y1476050D03*
X117449Y1702613D03*
X128180Y1098482D03*
Y1094482D03*
X142100Y1335800D03*
X131199Y1342050D03*
X131700Y1361000D03*
X151699Y517613D03*
X159399Y524850D03*
X166899D03*
X147200Y545000D03*
X182872Y90572D03*
Y86572D03*
X186599Y152000D03*
X174399Y524850D03*
X186599Y559300D03*
X174699Y916113D03*
X187099Y963100D03*
X174200Y1691200D03*
X186099Y1773200D03*
X202599Y1367400D03*
X229698Y287114D03*
X229699Y693550D03*
X233572Y92572D03*
X233699Y105050D03*
X241699Y95550D03*
X244000Y269700D03*
X243400Y677100D03*
X305699Y86613D03*
X308699Y334050D03*
Y339050D03*
X310199Y742050D03*
Y746050D03*
X306699Y1554550D03*
Y1558550D03*
X313921Y1944909D03*
Y1948909D03*
X319600Y105200D03*
X333198Y337114D03*
Y333114D03*
X318400Y365200D03*
X334699Y745050D03*
Y741050D03*
X319400Y772200D03*
X331199Y1553550D03*
Y1557550D03*
X318400Y1582600D03*
X321600Y1971900D03*
X339421Y1947409D03*
Y1943409D03*
X378800Y42300D03*
X700749Y1801634D03*
Y1808634D03*
X754678Y323924D03*
Y328924D03*
X753396Y724882D03*
Y729882D03*
X754033Y1126392D03*
Y1131392D03*
X757027Y1531296D03*
Y1536296D03*
X753514Y1937713D03*
Y1942213D03*
X779699Y326550D03*
Y322550D03*
X771678Y347924D03*
Y352424D03*
X777699Y724050D03*
Y728550D03*
X769896Y748382D03*
Y752882D03*
X778699Y1127550D03*
Y1123550D03*
X770033Y1152392D03*
Y1156892D03*
X780881Y1527893D03*
Y1531893D03*
X772527Y1554796D03*
Y1559296D03*
X778199Y1935050D03*
Y1939050D03*
X770014Y1960713D03*
Y1965213D03*
X800699Y336050D03*
Y332050D03*
X799199Y736050D03*
Y732050D03*
Y1133050D03*
Y1137050D03*
X801881Y1538893D03*
Y1542893D03*
X800381Y1944393D03*
Y1948393D03*
X816699Y167050D03*
X817199Y1788050D03*
X824199Y167050D03*
X831699D03*
X824699Y1788050D03*
X832199D03*
X849200Y276800D03*
X847900Y677700D03*
X847500Y1083200D03*
X849500Y1488100D03*
X849999Y1893850D03*
X873199Y1359550D03*
Y1363550D03*
Y1367550D03*
X905699Y107050D03*
Y103050D03*
X916099Y557800D03*
X916599Y962100D03*
X916099Y1771700D03*
X931099Y158500D03*
G54D16*
X18499Y1923750D03*
X103999Y1235250D03*
X104499Y1267813D03*
X102100Y1638700D03*
X105499Y1673313D03*
X134300Y455000D03*
X139499Y488813D03*
X162999Y852813D03*
X162499Y886313D03*
X221498Y281314D03*
X221499Y687750D03*
X217500Y1084200D03*
X220999Y1497750D03*
X227814Y1891313D03*
X253200Y1534900D03*
X289099Y23313D03*
X293999Y56313D03*
X853978Y275124D03*
X852696Y676082D03*
X852333Y1081592D03*
X854327Y1486496D03*
X854814Y1892313D03*
X894800Y1704200D03*
G54D43*
X49999Y1966250D03*
X107999Y1298313D03*
X109499Y1702813D03*
X143499Y517813D03*
X136600Y1174600D03*
X166499Y916313D03*
X218998Y312314D03*
X213598Y345314D03*
X218499Y719250D03*
X214599Y752250D03*
X217600Y1122200D03*
X217999Y1529250D03*
X218814Y1920313D03*
X213600Y1956800D03*
X297499Y86813D03*
X783049Y1813834D03*
X788049D03*
X858999Y306250D03*
X864900Y339300D03*
X855696Y706582D03*
X862896Y740782D03*
X855333Y1112092D03*
X862933Y1143592D03*
X857827Y1516996D03*
X865700Y1546800D03*
X857314Y1922813D03*
X864500Y1956600D03*
G54D70*
X185799Y95050D03*
X884201Y1693850D03*
X906299Y115050D03*
X896200Y1716200D03*
X971000Y1660500D03*
Y1665500D03*
G54D53*
X105749Y1964050D03*
X121249D03*
X206249Y39550D03*
X221749D03*
X915749Y44550D03*
X931249D03*
G54D26*
X20849Y1059925D03*
Y1052175D03*
X28349Y1056050D03*
X42449Y211775D03*
Y204025D03*
X49949Y207900D03*
X60449Y1846475D03*
Y1838725D03*
X74049Y648025D03*
Y655775D03*
X66549Y651900D03*
X67949Y1842600D03*
X137249Y1347675D03*
Y1355425D03*
X129749Y1351550D03*
X186049Y161200D03*
Y568400D03*
Y972100D03*
X186549Y1782500D03*
X193549Y157325D03*
Y165075D03*
Y564525D03*
Y572275D03*
Y968225D03*
Y975975D03*
X208049Y1372925D03*
Y1380675D03*
X200549Y1376800D03*
X194049Y1778625D03*
Y1786375D03*
X856449Y1358925D03*
X863949Y1362800D03*
X856449Y1366675D03*
X922049Y563025D03*
Y570775D03*
X914549Y566900D03*
X922049Y967225D03*
Y974975D03*
X914549Y971100D03*
X921549Y1777125D03*
Y1784875D03*
X914049Y1781000D03*
X939549Y163825D03*
Y171575D03*
X932049Y167700D03*
G54D35*
X34525Y1956355D03*
X36494D03*
X38462D03*
Y1937069D03*
X36494D03*
X34525D03*
X40431Y1956355D03*
X42399D03*
X44368D03*
X46337D03*
X48305D03*
X50274D03*
X52242D03*
X54211D03*
Y1937069D03*
X52242D03*
X50274D03*
X48305D03*
X46337D03*
X44368D03*
X42399D03*
X40431D03*
G54D80*
X666399Y1806699D03*
Y1808664D03*
Y1810634D03*
Y1812604D03*
Y1814569D03*
X682699Y1806699D03*
Y1814569D03*
Y1812604D03*
Y1810634D03*
Y1808664D03*
G54D17*
X18499Y1929350D03*
X103999Y1240850D03*
X104499Y1273413D03*
X102100Y1644300D03*
X105499Y1678913D03*
X134300Y460600D03*
X139499Y494413D03*
X162999Y858413D03*
X162499Y891913D03*
X221498Y286914D03*
X221499Y693350D03*
X217500Y1089800D03*
X220999Y1503350D03*
X227814Y1896913D03*
X253200Y1540500D03*
X289099Y28913D03*
X293999Y61913D03*
X853978Y280724D03*
X852696Y681682D03*
X852333Y1087192D03*
X854327Y1492096D03*
X854814Y1897913D03*
X894800Y1709800D03*
G54D71*
X210676Y72528D03*
X928499Y85550D03*
G54D62*
X122799Y1481750D03*
X159500Y818200D03*
X178999Y71250D03*
X213499Y97750D03*
X216998Y283814D03*
X216999Y690250D03*
X222900Y1086500D03*
X216999Y1500250D03*
X235499Y81250D03*
X232314Y1893813D03*
X312800Y317500D03*
X308999Y724750D03*
X309299Y1533150D03*
X313499Y1928250D03*
X655549Y1792834D03*
Y1800334D03*
X693549Y1798334D03*
Y1805834D03*
X755500Y706200D03*
X759500Y1919200D03*
X764500Y304700D03*
X779978Y304624D03*
X777500Y706200D03*
X760500Y1107200D03*
X778500D03*
X762000Y1513200D03*
X783200Y1512900D03*
X784500Y1919200D03*
X858478Y277624D03*
X857196Y678582D03*
X856833Y1084092D03*
X858827Y1488996D03*
X859314Y1894813D03*
X904499Y84750D03*
X928499Y108250D03*
G54D44*
X68898Y17047D03*
Y190275D03*
Y422559D03*
Y595787D03*
Y828071D03*
Y1001299D03*
Y1233583D03*
Y1406811D03*
Y1639095D03*
Y1812323D03*
X167323Y179803D03*
Y353031D03*
Y585315D03*
Y758543D03*
Y990827D03*
Y1164055D03*
Y1396339D03*
Y1569567D03*
Y1801851D03*
Y1975079D03*
X895669Y179803D03*
Y353031D03*
Y585315D03*
Y758543D03*
Y990827D03*
Y1164055D03*
Y1396339D03*
Y1569567D03*
Y1801851D03*
Y1975079D03*
G54D27*
X34599Y1588650D03*
X27030Y1925238D03*
X23030D03*
X19999Y1964850D03*
X31999Y1972350D03*
Y1964850D03*
X42700Y408900D03*
X49499Y1901850D03*
X83000Y1548300D03*
X79000D03*
X75000Y1565200D03*
X79000D03*
X97499Y1086850D03*
X101999D03*
X100700Y1107900D03*
X116499Y1223913D03*
Y1321413D03*
X120507Y1321496D03*
X116749Y1510150D03*
X112599D03*
X131999Y1224413D03*
X127499D03*
X162999Y443913D03*
X166999D03*
X150999Y440413D03*
X185999Y496450D03*
X181899D03*
X176499Y833413D03*
X185999Y842413D03*
X174499Y1649663D03*
X197499Y97850D03*
X205499D03*
X190499Y842413D03*
X205999Y898313D03*
X209999D03*
X226800Y1086600D03*
X225499Y1499350D03*
X231000Y1880500D03*
X247500Y1078550D03*
X236100Y1893900D03*
X280499Y341850D03*
X284999D03*
X281499Y748350D03*
X285499D03*
X278499Y1559350D03*
X282499D03*
X284358Y1951628D03*
X288358D03*
X399999Y39350D03*
X640049Y1803934D03*
Y1792934D03*
X649049Y1810934D03*
X655549Y1815434D03*
X712549Y1808634D03*
X706549Y1797934D03*
X744049Y1802934D03*
Y1795434D03*
Y1810434D03*
X833999Y204850D03*
X829499D03*
X827500Y267500D03*
X825700Y1075800D03*
X827700Y1480700D03*
X889700Y1704700D03*
X920499Y108350D03*
X912499D03*
X936499D03*
X948499D03*
G54D54*
X109439Y1079300D03*
X111999D03*
X114559D03*
Y1085800D03*
X109439D03*
X106939Y1210363D03*
X109499D03*
X112059D03*
Y1216863D03*
X106939D03*
X120059Y1311800D03*
X117499D03*
X114939D03*
Y1305300D03*
X120059D03*
X145439Y426863D03*
Y433363D03*
X132939Y1714800D03*
X135499D03*
X138059D03*
Y1721300D03*
X132939D03*
X147999Y426863D03*
X150559D03*
Y433363D03*
X167439Y820363D03*
Y826863D03*
X169999Y820363D03*
X172559D03*
Y826863D03*
X208559Y891800D03*
X205999D03*
X203439D03*
Y885300D03*
X208559D03*
X278939Y327300D03*
X284059D03*
Y333800D03*
X281499D03*
X278939D03*
X285059Y740300D03*
X282499D03*
X279939D03*
Y733800D03*
X285059D03*
X284059Y1551300D03*
X281499D03*
X278939D03*
Y1544800D03*
X284059D03*
X283589Y1936200D03*
X288709D03*
Y1942700D03*
X286149D03*
X283589D03*
X790559Y327800D03*
X787999D03*
X785439D03*
Y321300D03*
X790559D03*
X790059Y728800D03*
X787499D03*
X784939D03*
Y722300D03*
X790059D03*
X789559Y1131800D03*
X786999D03*
X784439D03*
Y1125300D03*
X789559D03*
X787693Y1529128D03*
X792813D03*
Y1535628D03*
X790253D03*
X787693D03*
X785939Y1935800D03*
X791059D03*
Y1942300D03*
X788499D03*
X785939D03*
G54D63*
X116045Y1484981D03*
X113485D03*
X110925D03*
X108365D03*
Y1501161D03*
X110925D03*
X113485D03*
X116045D03*
X166437Y533288D03*
X163877D03*
Y549468D03*
X166437D03*
X171557Y533288D03*
X168997D03*
Y549468D03*
X171557D03*
X833013Y176949D03*
X830453D03*
X827893D03*
X825333D03*
Y193129D03*
X827893D03*
X830453D03*
X833013D03*
Y1798997D03*
X830453D03*
X827893D03*
X825333D03*
Y1815177D03*
X827893D03*
X830453D03*
X833013D03*
G54D72*
X201033Y62685D03*
Y64654D03*
Y66622D03*
Y68591D03*
Y70559D03*
Y72528D03*
Y74497D03*
Y76465D03*
Y78434D03*
Y80402D03*
Y82371D03*
X220319Y72528D03*
Y70559D03*
Y68591D03*
Y66622D03*
Y64654D03*
Y62685D03*
Y82371D03*
Y80402D03*
Y78434D03*
Y76465D03*
Y74497D03*
X918856Y75707D03*
Y77676D03*
Y79644D03*
Y81613D03*
Y83581D03*
Y85550D03*
Y87519D03*
Y89487D03*
Y91456D03*
Y93424D03*
Y95393D03*
X938142Y93424D03*
Y91456D03*
Y89487D03*
Y87519D03*
Y85550D03*
Y83581D03*
Y81613D03*
Y79644D03*
Y77676D03*
Y75707D03*
Y95393D03*
G54D81*
X753949Y1801294D03*
Y1803854D03*
Y1806414D03*
Y1808974D03*
X776149Y1806414D03*
Y1803854D03*
Y1801294D03*
Y1808974D03*
G54D18*
X18199Y1956050D03*
X36199Y1918050D03*
X101145Y525988D03*
Y522488D03*
X99745Y931489D03*
Y927989D03*
X100528Y1336952D03*
Y1333452D03*
X104028Y1361952D03*
Y1358452D03*
X101699Y1743050D03*
Y1739550D03*
X103699Y1764050D03*
Y1767550D03*
X105199Y129550D03*
Y126050D03*
Y145050D03*
Y141550D03*
X105145Y550988D03*
Y547488D03*
X104745Y956489D03*
Y952989D03*
X129150Y1081100D03*
Y1077600D03*
X179699Y99050D03*
X178399Y524850D03*
X697749Y1813134D03*
X835699Y167550D03*
X836199Y1788050D03*
X903699Y124550D03*
X951199Y96050D03*
G54D45*
X78150Y28858D03*
Y178464D03*
Y434370D03*
Y583976D03*
Y839882D03*
Y989488D03*
Y1245394D03*
Y1395000D03*
Y1650906D03*
Y1800512D03*
X158071Y191614D03*
Y341220D03*
Y597126D03*
Y746732D03*
Y1002638D03*
Y1152244D03*
Y1408150D03*
Y1557756D03*
Y1813662D03*
Y1963268D03*
X886417Y191614D03*
Y341220D03*
Y597126D03*
Y746732D03*
Y1002638D03*
Y1152244D03*
Y1408150D03*
Y1557756D03*
Y1813662D03*
Y1963268D03*
G54D36*
X34799Y1946750D03*
X38703Y1946754D03*
X44368Y1951450D03*
X44399Y1942250D03*
X42532Y1946783D03*
X53999Y1946650D03*
X50299D03*
X46565Y1946703D03*
X205938Y72528D03*
X210605Y70692D03*
X210685Y74725D03*
X215138Y72559D03*
X210634Y66863D03*
X210638Y62959D03*
X210738Y82159D03*
Y78459D03*
X923761Y85550D03*
X928561Y95181D03*
X928428Y83714D03*
X928508Y87747D03*
X928561Y91481D03*
X928457Y79885D03*
X928461Y75981D03*
X932961Y85581D03*
G54D28*
X34599Y1592050D03*
X27030Y1928638D03*
X23030D03*
X19999Y1968250D03*
X31999Y1975750D03*
Y1968250D03*
X42700Y412300D03*
X49499Y1905250D03*
X83000Y1551700D03*
X79000D03*
X75000Y1568600D03*
X79000D03*
X97499Y1090250D03*
X101999D03*
X100700Y1111300D03*
X116499Y1227313D03*
Y1324813D03*
X120507Y1324896D03*
X116749Y1513550D03*
X112599D03*
X131999Y1227813D03*
X127499D03*
X162999Y447313D03*
X166999D03*
X150999Y443813D03*
X185999Y499850D03*
X181899D03*
X185999Y845813D03*
X176499Y836813D03*
X174499Y1653063D03*
X197499Y101250D03*
X205499D03*
X190499Y845813D03*
X205999Y901713D03*
X209999D03*
X226800Y1090000D03*
X225499Y1502750D03*
X231000Y1883900D03*
X247500Y1081950D03*
X236100Y1897300D03*
X280499Y345250D03*
X284999D03*
X281499Y751750D03*
X285499D03*
X278499Y1562750D03*
X282499D03*
X284358Y1955028D03*
X288358D03*
X399999Y42750D03*
X640049Y1807334D03*
Y1796334D03*
X649049Y1814334D03*
X655549Y1818834D03*
X706549Y1801334D03*
X712549Y1812034D03*
X744049Y1806334D03*
Y1798834D03*
Y1813834D03*
X833999Y208250D03*
X829499D03*
X827500Y270900D03*
X825700Y1079200D03*
X827700Y1484100D03*
X889700Y1708100D03*
X920499Y111750D03*
X912499D03*
X936499D03*
X948499D03*
G54D73*
X231500Y269350D03*
X227625Y276850D03*
X230900Y676250D03*
X227025Y683750D03*
X228825Y1493450D03*
X235375Y276850D03*
X234775Y683750D03*
X232700Y1485950D03*
X236575Y1493450D03*
X240100Y1880450D03*
X243975Y1887950D03*
X236225D03*
X836700Y267450D03*
X840575Y274950D03*
X832825D03*
X835300Y670150D03*
X839175Y677650D03*
X831425D03*
X835000Y1075750D03*
X838875Y1083250D03*
X831125D03*
X836900Y1479050D03*
X840775Y1486550D03*
X833025D03*
X837499Y1884800D03*
X841374Y1892300D03*
X833624D03*
G54D46*
X85630Y41141D03*
Y46141D03*
Y51141D03*
Y56141D03*
Y61141D03*
Y66141D03*
Y71141D03*
Y76141D03*
Y81141D03*
Y86141D03*
Y91141D03*
Y96141D03*
Y101141D03*
Y106141D03*
Y111141D03*
Y136141D03*
Y141141D03*
Y146141D03*
Y151141D03*
Y156141D03*
Y161141D03*
Y166141D03*
Y446653D03*
Y451653D03*
Y456653D03*
Y461653D03*
Y466653D03*
Y471653D03*
Y476653D03*
Y481653D03*
Y486653D03*
Y491653D03*
Y496653D03*
Y501653D03*
Y506653D03*
Y511653D03*
Y516653D03*
Y541653D03*
Y546653D03*
Y551653D03*
Y556653D03*
Y561653D03*
Y566653D03*
Y571653D03*
Y852165D03*
Y857165D03*
Y862165D03*
Y867165D03*
Y872165D03*
Y877165D03*
Y882165D03*
Y887165D03*
Y892165D03*
Y897165D03*
Y902165D03*
Y907165D03*
Y912165D03*
Y917165D03*
Y922165D03*
Y947165D03*
Y952165D03*
Y957165D03*
Y962165D03*
Y967165D03*
Y972165D03*
Y977165D03*
Y1257677D03*
Y1262677D03*
Y1267677D03*
Y1272677D03*
Y1277677D03*
Y1282677D03*
Y1287677D03*
Y1292677D03*
Y1297677D03*
Y1302677D03*
Y1307677D03*
Y1312677D03*
Y1317677D03*
Y1322677D03*
Y1327677D03*
Y1352677D03*
Y1357677D03*
Y1362677D03*
Y1367677D03*
Y1372677D03*
Y1377677D03*
Y1382677D03*
Y1663189D03*
Y1668189D03*
Y1673189D03*
Y1678189D03*
Y1683189D03*
Y1688189D03*
Y1693189D03*
Y1698189D03*
Y1703189D03*
Y1708189D03*
Y1713189D03*
Y1718189D03*
Y1723189D03*
Y1728189D03*
Y1733189D03*
Y1758189D03*
Y1763189D03*
Y1768189D03*
Y1773189D03*
Y1778189D03*
Y1783189D03*
Y1788189D03*
X150591Y218937D03*
Y213937D03*
Y208937D03*
Y203937D03*
Y233937D03*
Y228937D03*
Y223937D03*
Y263937D03*
Y258937D03*
Y283937D03*
Y278937D03*
Y273937D03*
Y268937D03*
Y303937D03*
Y298937D03*
Y293937D03*
Y288937D03*
Y323937D03*
Y318937D03*
Y313937D03*
Y308937D03*
Y328937D03*
Y624449D03*
Y619449D03*
Y614449D03*
Y609449D03*
Y639449D03*
Y634449D03*
Y629449D03*
Y664449D03*
Y684449D03*
Y679449D03*
Y674449D03*
Y669449D03*
Y704449D03*
Y699449D03*
Y694449D03*
Y689449D03*
Y729449D03*
Y724449D03*
Y719449D03*
Y714449D03*
Y709449D03*
Y734449D03*
Y1024961D03*
Y1019961D03*
Y1014961D03*
Y1044961D03*
Y1039961D03*
Y1034961D03*
Y1029961D03*
Y1084961D03*
Y1079961D03*
Y1074961D03*
Y1069961D03*
Y1109961D03*
Y1104961D03*
Y1099961D03*
Y1094961D03*
Y1089961D03*
Y1129961D03*
Y1124961D03*
Y1119961D03*
Y1114961D03*
Y1139961D03*
Y1134961D03*
Y1425473D03*
Y1420473D03*
Y1445473D03*
Y1440473D03*
Y1435473D03*
Y1430473D03*
Y1450473D03*
Y1490473D03*
Y1485473D03*
Y1480473D03*
Y1475473D03*
Y1510473D03*
Y1505473D03*
Y1500473D03*
Y1495473D03*
Y1530473D03*
Y1525473D03*
Y1520473D03*
Y1515473D03*
Y1545473D03*
Y1540473D03*
Y1535473D03*
Y1825985D03*
Y1850985D03*
Y1845985D03*
Y1840985D03*
Y1835985D03*
Y1830985D03*
Y1855985D03*
Y1890985D03*
Y1885985D03*
Y1880985D03*
Y1910985D03*
Y1905985D03*
Y1900985D03*
Y1895985D03*
Y1930985D03*
Y1925985D03*
Y1920985D03*
Y1915985D03*
Y1950985D03*
Y1945985D03*
Y1940985D03*
Y1935985D03*
X878937Y218937D03*
Y213937D03*
Y208937D03*
Y203937D03*
Y233937D03*
Y228937D03*
Y223937D03*
Y263937D03*
Y258937D03*
Y283937D03*
Y278937D03*
Y273937D03*
Y268937D03*
Y303937D03*
Y298937D03*
Y293937D03*
Y288937D03*
Y323937D03*
Y318937D03*
Y313937D03*
Y308937D03*
Y328937D03*
Y624449D03*
Y619449D03*
Y614449D03*
Y609449D03*
Y639449D03*
Y634449D03*
Y629449D03*
Y664449D03*
Y684449D03*
Y679449D03*
Y674449D03*
Y669449D03*
Y704449D03*
Y699449D03*
Y694449D03*
Y689449D03*
Y729449D03*
Y724449D03*
Y719449D03*
Y714449D03*
Y709449D03*
Y734449D03*
Y1024961D03*
Y1019961D03*
Y1014961D03*
Y1044961D03*
Y1039961D03*
Y1034961D03*
Y1029961D03*
Y1084961D03*
Y1079961D03*
Y1074961D03*
Y1069961D03*
Y1109961D03*
Y1104961D03*
Y1099961D03*
Y1094961D03*
Y1089961D03*
Y1129961D03*
Y1124961D03*
Y1119961D03*
Y1114961D03*
Y1139961D03*
Y1134961D03*
Y1425473D03*
Y1420473D03*
Y1445473D03*
Y1440473D03*
Y1435473D03*
Y1430473D03*
Y1450473D03*
Y1490473D03*
Y1485473D03*
Y1480473D03*
Y1475473D03*
Y1510473D03*
Y1505473D03*
Y1500473D03*
Y1495473D03*
Y1530473D03*
Y1525473D03*
Y1520473D03*
Y1515473D03*
Y1545473D03*
Y1540473D03*
Y1535473D03*
Y1825985D03*
Y1850985D03*
Y1845985D03*
Y1840985D03*
Y1835985D03*
Y1830985D03*
Y1855985D03*
Y1890985D03*
Y1885985D03*
Y1880985D03*
Y1910985D03*
Y1905985D03*
Y1900985D03*
Y1895985D03*
Y1930985D03*
Y1925985D03*
Y1920985D03*
Y1915985D03*
Y1950985D03*
Y1945985D03*
Y1940985D03*
Y1935985D03*
G54D37*
X37999Y1968750D03*
Y1976350D03*
X53999Y778750D03*
Y786350D03*
X57068Y1966462D03*
Y1974062D03*
X83568Y1966462D03*
Y1974062D03*
X74568Y1966462D03*
Y1974062D03*
X65768Y1966462D03*
Y1974062D03*
X92568Y1966462D03*
Y1974062D03*
X240999Y89850D03*
Y82250D03*
G54D82*
X825300Y1726200D03*
X836300D03*
X888200Y1727300D03*
X877200D03*
X940400Y1486900D03*
X951400D03*
X940500Y1477500D03*
X951500D03*
G54D64*
X143999Y54089D03*
Y89011D03*
X862999Y60089D03*
Y95011D03*
G54D55*
X113499Y1106640D03*
Y1109200D03*
X106099D03*
Y1106640D03*
X113499Y1111760D03*
X106099D03*
X123299Y1216113D03*
Y1213553D03*
Y1218673D03*
X130699Y1213553D03*
Y1216113D03*
Y1218673D03*
X147400Y1324540D03*
Y1327100D03*
Y1329660D03*
X140000D03*
Y1327100D03*
Y1324540D03*
X158299Y433053D03*
X165699D03*
X158299Y438173D03*
Y435613D03*
X165699D03*
Y438173D03*
X181799Y834113D03*
Y831553D03*
X189199D03*
Y834113D03*
X181799Y836673D03*
X189199D03*
X179999Y1652987D03*
Y1650427D03*
Y1647867D03*
X187399D03*
Y1650427D03*
Y1652987D03*
X218100Y1882960D03*
Y1880400D03*
Y1877840D03*
X225500D03*
Y1880400D03*
Y1882960D03*
X242000Y1069000D03*
Y1071560D03*
Y1074120D03*
X234600D03*
Y1071560D03*
Y1069000D03*
X233600Y1478360D03*
Y1475800D03*
Y1473240D03*
X241000D03*
Y1475800D03*
Y1478360D03*
X324800Y92340D03*
Y94900D03*
X317400D03*
Y92340D03*
X324800Y97460D03*
X317400D03*
X394199Y36490D03*
Y39050D03*
Y41610D03*
X386799D03*
Y39050D03*
Y36490D03*
X760778Y341984D03*
Y339424D03*
Y336864D03*
X758996Y742442D03*
Y739882D03*
Y737322D03*
X760799Y1146610D03*
Y1144050D03*
Y1141490D03*
X759114Y1954773D03*
Y1952213D03*
Y1949653D03*
X768178Y336864D03*
Y339424D03*
Y341984D03*
X766396Y737322D03*
Y739882D03*
Y742442D03*
X768199Y1141490D03*
Y1144050D03*
Y1146610D03*
X761627Y1548856D03*
Y1546296D03*
Y1543736D03*
X769027D03*
Y1546296D03*
Y1548856D03*
X766514Y1949653D03*
Y1952213D03*
Y1954773D03*
X814700Y270060D03*
Y267500D03*
Y264940D03*
X822100D03*
Y267500D03*
Y270060D03*
X813200Y672660D03*
Y670100D03*
Y667540D03*
X820600D03*
Y670100D03*
Y672660D03*
X812900Y1075460D03*
Y1072900D03*
Y1070340D03*
X820300D03*
Y1072900D03*
Y1075460D03*
X814700Y1483160D03*
Y1480600D03*
Y1478040D03*
X822100D03*
Y1480600D03*
Y1483160D03*
X815300Y1887560D03*
Y1885000D03*
Y1882440D03*
X822700D03*
Y1885000D03*
Y1887560D03*
G54D19*
X18299Y1948050D03*
Y1952050D03*
Y1940050D03*
X31299Y611550D03*
X55799Y203550D03*
Y207550D03*
Y211550D03*
X56299Y1017050D03*
X56236Y1021050D03*
Y1025050D03*
X52299Y1897050D03*
X77799Y204550D03*
Y208550D03*
X77801Y611450D03*
Y615450D03*
X81300Y1008500D03*
X82549Y1828613D03*
X73799Y1837550D03*
X74049Y1843113D03*
X82549Y1832613D03*
X73799Y1849050D03*
X97300Y1115400D03*
X100549Y1476050D03*
X105550Y972000D03*
X105499Y967850D03*
X124780Y1098482D03*
Y1094482D03*
X112799Y1298113D03*
X108049Y1476050D03*
X114049Y1702613D03*
X143800Y545000D03*
X138700Y1335800D03*
X127799Y1342050D03*
X128300Y1361000D03*
X148299Y517613D03*
X155999Y524850D03*
X163499D03*
X179472Y90572D03*
Y86572D03*
X183199Y152000D03*
X170999Y524850D03*
X183199Y559300D03*
X171299Y916113D03*
X183699Y963100D03*
X170800Y1691200D03*
X182699Y1773200D03*
X199199Y1367400D03*
X230172Y92572D03*
X230299Y105050D03*
X226298Y287114D03*
X226299Y693550D03*
X238299Y95550D03*
X240600Y269700D03*
X240000Y677100D03*
X302299Y86613D03*
X305299Y334050D03*
Y339050D03*
X315000Y365200D03*
X306799Y742050D03*
Y746050D03*
X303299Y1554550D03*
Y1558550D03*
X315000Y1582600D03*
X310521Y1944909D03*
Y1948909D03*
X316200Y105200D03*
X329798Y337114D03*
Y333114D03*
X331299Y745050D03*
Y741050D03*
X316000Y772200D03*
X327799Y1553550D03*
Y1557550D03*
X336021Y1947409D03*
Y1943409D03*
X318200Y1971900D03*
X375400Y42300D03*
X697349Y1801634D03*
Y1808634D03*
X751278Y323924D03*
Y328924D03*
X749996Y724882D03*
Y729882D03*
X750633Y1126392D03*
Y1131392D03*
X753627Y1531296D03*
Y1536296D03*
X750114Y1937713D03*
Y1942213D03*
X776299Y326550D03*
Y322550D03*
X768278Y347924D03*
Y352424D03*
X774299Y724050D03*
Y728550D03*
X766496Y748382D03*
Y752882D03*
X775299Y1127550D03*
Y1123550D03*
X766633Y1152392D03*
Y1156892D03*
X777481Y1527893D03*
Y1531893D03*
X769127Y1554796D03*
Y1559296D03*
X774799Y1935050D03*
Y1939050D03*
X766614Y1960713D03*
Y1965213D03*
X797299Y336050D03*
Y332050D03*
X795799Y736050D03*
Y732050D03*
Y1133050D03*
Y1137050D03*
X798481Y1538893D03*
Y1542893D03*
X796981Y1944393D03*
Y1948393D03*
X813299Y167050D03*
X820799D03*
X813799Y1788050D03*
X821299D03*
X828299Y167050D03*
X844500Y677700D03*
X844100Y1083200D03*
X828799Y1788050D03*
X845800Y276800D03*
X846100Y1488100D03*
X846599Y1893850D03*
X869799Y1359550D03*
Y1363550D03*
Y1367550D03*
X902299Y107050D03*
Y103050D03*
X927699Y158500D03*
X912699Y557800D03*
X913199Y962100D03*
X912699Y1771700D03*
G54D83*
X854101Y1710351D03*
Y1733149D03*
G54D56*
X116249Y1093990D03*
Y1096550D03*
Y1099110D03*
X109749D03*
Y1093990D03*
X117249Y1720110D03*
Y1717550D03*
Y1714990D03*
X123749D03*
Y1720110D03*
X176999Y490913D03*
Y488353D03*
Y485793D03*
X183499D03*
Y490913D03*
X315248Y339174D03*
Y334054D03*
X316749Y746110D03*
Y740990D03*
X313249Y1554490D03*
Y1559610D03*
X321748Y334054D03*
Y336614D03*
Y339174D03*
X323249Y740990D03*
Y743550D03*
Y746110D03*
X319749Y1554490D03*
Y1557050D03*
Y1559610D03*
X326971Y1944349D03*
Y1946909D03*
Y1949469D03*
X320471D03*
Y1944349D03*
X347749Y67110D03*
Y64550D03*
Y61990D03*
X354249D03*
Y67110D03*
X387749Y50990D03*
X394249D03*
X387749Y56110D03*
Y53550D03*
X394249Y56110D03*
X761228Y323864D03*
Y328984D03*
X760446Y724822D03*
Y729942D03*
X760583Y1131452D03*
Y1126332D03*
X760064Y1942273D03*
Y1937153D03*
X767728Y323864D03*
Y326424D03*
Y328984D03*
X766946Y724822D03*
Y727382D03*
Y729942D03*
X767083Y1126332D03*
Y1128892D03*
Y1131452D03*
X770077Y1531236D03*
X763577D03*
X770077Y1533796D03*
Y1536356D03*
X763577D03*
X766564Y1937153D03*
Y1939713D03*
Y1942273D03*
G54D47*
X77166Y114212D03*
Y117362D03*
Y120511D03*
Y123661D03*
Y126811D03*
Y129960D03*
Y133110D03*
Y519724D03*
Y522874D03*
Y526023D03*
Y529173D03*
Y532323D03*
Y535472D03*
Y538622D03*
Y925236D03*
Y928386D03*
Y931535D03*
Y934685D03*
Y937835D03*
Y940984D03*
Y944134D03*
Y1330748D03*
Y1333898D03*
Y1337047D03*
Y1340197D03*
Y1343347D03*
Y1346496D03*
Y1349646D03*
Y1736260D03*
Y1739410D03*
Y1742559D03*
Y1745709D03*
Y1748859D03*
Y1752008D03*
Y1755158D03*
X159055Y243267D03*
Y240118D03*
Y236968D03*
Y255866D03*
Y252716D03*
Y249567D03*
Y246417D03*
Y642480D03*
Y661378D03*
Y658228D03*
Y655079D03*
Y651929D03*
Y648779D03*
Y645630D03*
Y1066890D03*
Y1063740D03*
Y1060591D03*
Y1057441D03*
Y1054291D03*
Y1051142D03*
Y1047992D03*
Y1469252D03*
Y1466103D03*
Y1462953D03*
Y1459803D03*
Y1456654D03*
Y1453504D03*
Y1472402D03*
Y1871615D03*
Y1868465D03*
Y1865315D03*
Y1862166D03*
Y1859016D03*
Y1877914D03*
Y1874764D03*
X887401Y243267D03*
Y240118D03*
Y236968D03*
Y255866D03*
Y252716D03*
Y249567D03*
Y246417D03*
Y642480D03*
Y661378D03*
Y658228D03*
Y655079D03*
Y651929D03*
Y648779D03*
Y645630D03*
Y1066890D03*
Y1063740D03*
Y1060591D03*
Y1057441D03*
Y1054291D03*
Y1051142D03*
Y1047992D03*
Y1469252D03*
Y1466103D03*
Y1462953D03*
Y1459803D03*
Y1456654D03*
Y1453504D03*
Y1472402D03*
Y1871615D03*
Y1868465D03*
Y1865315D03*
Y1862166D03*
Y1859016D03*
Y1877914D03*
Y1874764D03*
G54D65*
X140940Y550300D03*
X143500D03*
X146060D03*
Y557700D03*
X143500D03*
X140940D03*
X181340Y937100D03*
X183900D03*
X186460D03*
Y944500D03*
X183900D03*
X181340D03*
X172240Y1678400D03*
X174800D03*
X177360D03*
Y1685800D03*
X174800D03*
X172240D03*
X242040Y275100D03*
X244600D03*
X247160D03*
Y282500D03*
X244600D03*
X242040D03*
X241440Y682500D03*
X244000D03*
X246560D03*
Y689900D03*
X244000D03*
X241440D03*
X315939Y352350D03*
X318499D03*
X321059D03*
Y359750D03*
X318499D03*
X315939D03*
X316939Y759350D03*
X319499D03*
X322059D03*
Y766750D03*
X319499D03*
X316939D03*
X315939Y1569850D03*
X318499D03*
X321059D03*
Y1577250D03*
X318499D03*
X315939D03*
X319080Y1959072D03*
X321640D03*
X324200D03*
Y1966472D03*
X321640D03*
X319080D03*
G54D74*
X242299Y76550D03*
X958299Y89550D03*
G54D29*
X30499Y1592060D03*
X31999Y1922250D03*
X23999Y1968250D03*
X27999D03*
X46800Y412300D03*
X42900Y604800D03*
X103999Y1472000D03*
X119499Y1109750D03*
X109499Y1201813D03*
X105499D03*
X106999Y1227313D03*
X111999D03*
X111499Y1472000D03*
X115599Y1471950D03*
X141499Y443813D03*
X146499D03*
X136000Y532200D03*
X135999Y1706750D03*
X131999D03*
X159199Y520550D03*
X167199D03*
X166499Y812313D03*
X167499Y836813D03*
X152600Y1684600D03*
X174999Y74750D03*
X185499Y120750D03*
X174199Y520550D03*
X170499Y812313D03*
X172499Y836813D03*
X184600Y1376500D03*
X180500D03*
X201499Y101250D03*
X209499D03*
X192800Y1654500D03*
X217499Y101250D03*
X223436Y1897065D03*
X644049Y1807334D03*
Y1796334D03*
X710549Y1801334D03*
X708549Y1812034D03*
X754978Y339124D03*
X753196Y738582D03*
X755499Y1143750D03*
X756327Y1546496D03*
X753314Y1951913D03*
X816499Y162750D03*
X814999Y1783750D03*
X823999Y162750D03*
X831499D03*
X826100Y670100D03*
X833499Y1783750D03*
X824499D03*
X828000Y1884700D03*
X900499Y88250D03*
X903499Y131750D03*
X924499Y111750D03*
X916499D03*
X932499D03*
X944499D03*
X940499D03*
X952499D03*
G54D38*
X62499Y733150D03*
Y759950D03*
X86499Y1147150D03*
Y1173950D03*
X104000Y1571600D03*
Y1598400D03*
X151499Y1634087D03*
Y1660887D03*
X262998Y333214D03*
Y360014D03*
X263999Y738650D03*
Y765450D03*
X262999Y1549650D03*
Y1576450D03*
Y1946150D03*
Y1972950D03*
X339499Y24650D03*
Y51450D03*
X815499Y326150D03*
Y352950D03*
X813499Y729150D03*
Y755950D03*
Y1131650D03*
Y1158450D03*
X816171Y1536904D03*
Y1563704D03*
X814999Y1940650D03*
Y1967450D03*
G54D39*
X63999Y1871050D03*
Y1882050D03*
X72999Y1871550D03*
Y1882550D03*
X102999Y1171550D03*
Y1182550D03*
X111999Y1171550D03*
X120999D03*
X111999Y1182550D03*
X120999D03*
X120499Y1233613D03*
X111499D03*
X120499Y1244613D03*
X111499D03*
Y1266613D03*
Y1277613D03*
X126199Y1638013D03*
X117500Y1638000D03*
X108799Y1638013D03*
X126199Y1649013D03*
X117500Y1649000D03*
X108799Y1649013D03*
X112499Y1671613D03*
Y1682613D03*
X140999Y453113D03*
Y464113D03*
X146499Y486613D03*
Y497613D03*
X129900Y1171500D03*
Y1182500D03*
X129499Y1233613D03*
X132700Y1254400D03*
X129499Y1244613D03*
X132700Y1265400D03*
X133999Y1659613D03*
Y1670613D03*
X158999Y453113D03*
X149999D03*
X167900Y453100D03*
X158999Y464113D03*
X149999D03*
X167900Y464100D03*
X169499Y885113D03*
Y896113D03*
X169999Y112550D03*
X178999D03*
X169999Y123550D03*
X178999D03*
X187999Y851613D03*
X178999D03*
X169999D03*
X187999Y862613D03*
X178999D03*
X169999D03*
X191499Y873113D03*
Y884113D03*
X225900Y307400D03*
Y318400D03*
X228998Y340614D03*
X220298D03*
X228998Y351614D03*
X220298D03*
X225499Y726050D03*
Y715050D03*
X229999Y749550D03*
X221299D03*
X229999Y760550D03*
X221299D03*
X224300Y1130200D03*
Y1119200D03*
X224999Y1524550D03*
Y1535550D03*
X229000Y1568100D03*
Y1557100D03*
X220300Y1568100D03*
Y1557100D03*
X225814Y1931113D03*
Y1920113D03*
X220300Y1953600D03*
X229000D03*
X220300Y1964600D03*
X229000D03*
X246498Y319114D03*
Y330114D03*
X237698Y340614D03*
Y351614D03*
X246499Y726050D03*
Y737050D03*
X238699Y749550D03*
Y760550D03*
X246499Y1535550D03*
Y1546550D03*
X237700Y1568100D03*
Y1557100D03*
X246314Y1934113D03*
Y1945113D03*
X237700Y1953600D03*
Y1964600D03*
X296099Y22113D03*
Y33113D03*
X314099Y22113D03*
Y33113D03*
X305099Y22113D03*
Y33113D03*
X300999Y55613D03*
Y66613D03*
X322499Y43613D03*
Y54613D03*
X832978Y313424D03*
Y324424D03*
X840800Y346800D03*
Y335800D03*
X830499Y715550D03*
Y726550D03*
X838796Y747582D03*
Y736582D03*
X830499Y1119550D03*
Y1130550D03*
X838833Y1152392D03*
Y1141392D03*
X833827Y1523796D03*
Y1534796D03*
X841500Y1556300D03*
Y1545300D03*
X832499Y1930050D03*
X840400Y1954000D03*
X832499Y1941050D03*
X840400Y1965000D03*
X846999Y135550D03*
Y124550D03*
X850999Y301550D03*
Y312550D03*
X849500Y346800D03*
Y335800D03*
X858200Y346800D03*
Y335800D03*
X848696Y702882D03*
Y713882D03*
X847496Y747582D03*
Y736582D03*
X856196Y747582D03*
Y736582D03*
X848413Y1107613D03*
Y1118613D03*
X847533Y1152392D03*
Y1141392D03*
X856233Y1152392D03*
Y1141392D03*
X850827Y1512296D03*
Y1523296D03*
X850200Y1556300D03*
Y1545300D03*
X858900Y1556300D03*
Y1545300D03*
X850314Y1929113D03*
Y1918113D03*
X849100Y1954000D03*
X857800D03*
X849100Y1965000D03*
X857800D03*
X896999Y136550D03*
Y125550D03*
G54D48*
X71773Y209631D03*
Y206431D03*
X66023Y209631D03*
Y206431D03*
X71773Y615143D03*
Y611943D03*
X66023Y615143D03*
Y611943D03*
X71773Y1020655D03*
Y1017455D03*
X66023Y1020655D03*
Y1017455D03*
X71773Y1426167D03*
Y1422967D03*
X66023Y1426167D03*
Y1422967D03*
X71773Y1828479D03*
X66023D03*
X71773Y1831679D03*
X66023D03*
X164448Y160447D03*
Y163647D03*
Y565959D03*
Y569159D03*
Y971471D03*
Y974671D03*
Y1376983D03*
Y1380183D03*
Y1782494D03*
Y1785694D03*
X170198Y160447D03*
Y163647D03*
Y565959D03*
Y569159D03*
Y971471D03*
Y974671D03*
Y1376983D03*
Y1380183D03*
Y1782494D03*
Y1785694D03*
X892794Y160447D03*
Y163647D03*
X898544Y160447D03*
Y163647D03*
X892794Y565959D03*
Y569159D03*
X898544Y565959D03*
Y569159D03*
X892794Y971471D03*
Y974671D03*
X898544Y971471D03*
Y974671D03*
X892794Y1376983D03*
Y1380183D03*
X898544Y1376983D03*
Y1380183D03*
X892794Y1782494D03*
Y1785694D03*
X898544Y1782494D03*
Y1785694D03*
G54D84*
X876000Y1703899D03*
X879750D03*
X883500D03*
Y1714499D03*
X879750D03*
X876000D03*
G54D75*
X236699Y76550D03*
X952699Y89550D03*
G54D66*
X144099Y1247113D03*
X170899D03*
X179100Y461000D03*
X205900D03*
X203099Y859613D03*
X229899D03*
G54D57*
X117999Y1143550D03*
Y1162050D03*
G54D76*
X238249Y102050D03*
G54D49*
X67999Y774150D03*
Y798950D03*
X133521Y107677D03*
Y132477D03*
X154521Y107677D03*
Y132477D03*
X861999Y114650D03*
Y139450D03*
X882499Y114650D03*
Y139450D03*
G54D85*
X1019291Y1416024D03*
Y1694212D03*
G54D67*
X128099Y1598150D03*
X135699D03*
X232199Y33550D03*
Y42550D03*
Y51550D03*
Y69550D03*
Y60550D03*
X239799Y33550D03*
Y42550D03*
Y51550D03*
Y69550D03*
Y60550D03*
X951199Y46050D03*
Y55050D03*
Y64050D03*
Y73050D03*
Y82050D03*
X949199Y101550D03*
X958799Y46050D03*
Y55050D03*
Y64050D03*
Y73050D03*
Y82050D03*
X956799Y101550D03*
G54D58*
X105749Y1255113D03*
X124249D03*
X105749Y1288613D03*
X124249D03*
X106749Y1659613D03*
X125249D03*
X107249Y1693113D03*
X125749D03*
X140749Y474550D03*
X140999Y508113D03*
X159249Y474550D03*
X159499Y508113D03*
X164249Y873113D03*
Y906613D03*
X182749Y873113D03*
Y906613D03*
X219248Y296614D03*
Y329614D03*
X219749Y703050D03*
X219249Y737050D03*
X219250Y1103100D03*
X218050Y1513400D03*
X219249Y1546050D03*
X219684Y1906687D03*
X218184Y1942987D03*
X237748Y296614D03*
Y329614D03*
X238249Y703050D03*
X237749Y737050D03*
X237750Y1103100D03*
X236550Y1513400D03*
X237749Y1546050D03*
X238184Y1906687D03*
X236684Y1942987D03*
X295249Y43613D03*
Y77113D03*
X313749Y43613D03*
Y77113D03*
X837978Y290124D03*
X841478Y323924D03*
X836196Y691182D03*
X839249Y724550D03*
X836333Y1096692D03*
X839749Y1129550D03*
X838077Y1501596D03*
X842577Y1534296D03*
X838314Y1907313D03*
X841249Y1940550D03*
X856478Y290124D03*
X859978Y323924D03*
X854696Y691182D03*
X857749Y724550D03*
X854833Y1096692D03*
X858249Y1129550D03*
X856577Y1501596D03*
X861077Y1534296D03*
X856814Y1907313D03*
X859749Y1940550D03*
G54D59*
X120418Y1275613D03*
X121418Y1680113D03*
X131580Y1275613D03*
X132580Y1680113D03*
X155158Y495113D03*
X166320D03*
X178418Y893613D03*
X189580D03*
X233917Y309614D03*
X245079D03*
X234418Y716550D03*
X245580D03*
X233918Y1526050D03*
X245080D03*
X235843Y1920987D03*
X247005D03*
X309918Y64113D03*
X321080D03*
X842119Y303424D03*
X830957D03*
X840037Y704382D03*
X828875D03*
X840174Y1109892D03*
X829012D03*
X841708Y1514296D03*
X830546D03*
X841655Y1920613D03*
X830493D03*
G54D68*
X166499Y1277113D03*
X161499D03*
X156499D03*
Y1297113D03*
X161499D03*
X166499D03*
X167499Y1700113D03*
X162499D03*
X157499D03*
Y1720113D03*
X162499D03*
X167499D03*
X171499Y1277113D03*
Y1297113D03*
X172499Y1700113D03*
Y1720113D03*
X206499Y514113D03*
X201499D03*
X196499D03*
X191499D03*
Y534113D03*
X196499D03*
X201499D03*
X206499D03*
X229999Y912613D03*
X224999D03*
X219999D03*
X214999D03*
Y932613D03*
X219999D03*
X224999D03*
X229999D03*
X247299Y1136650D03*
X242299D03*
X237299D03*
X232299D03*
Y1156650D03*
X237299D03*
X242299D03*
X247299D03*
X355999Y86550D03*
X350999D03*
X345999D03*
Y106550D03*
X350999D03*
X355999D03*
X360999Y86550D03*
Y106550D03*
G54D77*
X240749Y102050D03*
G54D86*
X1005807Y1636102D03*
Y1631102D03*
Y1626102D03*
Y1621102D03*
Y1661102D03*
Y1656102D03*
Y1651102D03*
Y1646102D03*
Y1641102D03*
Y1676102D03*
Y1671102D03*
Y1666102D03*
G54D87*
G01X-87137Y-139897D02*
Y-107897D01*
G01X-75137Y-123897D02*
G02I-12000J0D01*
G01X-80287D02*
G02I-6850J0D01*
G01X-71137D02*
X-103137D01*
G01X-71137Y-139897D02*
Y-219897D01*
G01D02*
X1129963D01*
G01X-71137Y-175397D02*
X1129963D01*
G01X-71137Y-139897D02*
X1129963D01*
G01X342463D02*
Y-219897D01*
G01X479963Y-139897D02*
Y-219897D01*
G01X594963Y-139897D02*
Y-219897D01*
G01X762463Y-139897D02*
Y-219897D01*
G01X932463Y-139897D02*
Y-219897D01*
G01X1129963Y-139897D02*
Y-219897D01*
G01X1157963Y-123897D02*
G02I-12000J0D01*
G01X1152813D02*
G02I-6850J0D01*
G01X1161963D02*
X1129963D01*
G01X1145963Y-139897D02*
Y-107897D01*
G54D69*
X180199Y95050D03*
X878601Y1693850D03*
X900699Y115050D03*
X890600Y1716200D03*
X965400Y1660500D03*
Y1665500D03*
G54D78*
X241500Y1085625D03*
X234000Y1089500D03*
Y1081750D03*
G54D88*
G01X-53190Y-209897D02*
Y-192397D01*
G01X-44894D02*
X-53190Y-203189D01*
G01X-43584Y-209897D02*
X-49479Y-198231D01*
G01X-35909Y-209897D02*
Y-192397D01*
X-25865Y-209897D01*
Y-192397D01*
G01X-13387Y-209897D02*
X-15134Y-209605D01*
X-16662Y-208439D01*
X-17972Y-206689D01*
X-18846Y-204647D01*
X-19282Y-202314D01*
Y-199980D01*
X-18846Y-197647D01*
X-17972Y-195605D01*
X-16662Y-193856D01*
X-15134Y-192689D01*
X-13387Y-192397D01*
X-11641Y-192689D01*
X-10112Y-193856D01*
X-8802Y-195605D01*
X-7928Y-197647D01*
X-7492Y-199980D01*
Y-202314D01*
X-7928Y-204647D01*
X-8802Y-206689D01*
X-10112Y-208439D01*
X-11641Y-209605D01*
X-13387Y-209897D01*
G01X-472D02*
X8698Y-192397D01*
G01X-472D02*
X8698Y-209897D01*
G01X34310D02*
Y-192397D01*
X38676D01*
X40423Y-193272D01*
X41733Y-194439D01*
X42825Y-196188D01*
X43698Y-198231D01*
X43916Y-201147D01*
X43698Y-204064D01*
X42825Y-206106D01*
X41733Y-207856D01*
X40423Y-209022D01*
X38676Y-209897D01*
X34310D01*
G01X52246D02*
Y-192397D01*
X57705D01*
X59451Y-193272D01*
X60543Y-194439D01*
X60980Y-196772D01*
X60543Y-199106D01*
X59233Y-200564D01*
X57705Y-201439D01*
X52246D01*
G01X57705D02*
X60980Y-209897D01*
G01X71493Y-192397D02*
X76733D01*
G01X74113D02*
Y-209897D01*
G01X71493D02*
X76733D01*
G01X86154Y-192397D02*
X91613Y-209897D01*
X97072Y-192397D01*
G01X113480Y-209897D02*
X104746D01*
Y-192397D01*
X113480D01*
G01X109986Y-200855D02*
X104746D01*
G01X139746Y-209897D02*
Y-192397D01*
X144986D01*
X146733Y-193272D01*
X148043Y-195314D01*
X148480Y-197647D01*
X148043Y-199980D01*
X146951Y-201730D01*
X144986Y-202606D01*
X139746D01*
G01X157246Y-192397D02*
Y-209897D01*
X165980D01*
G01X173654D02*
X179113Y-192397D01*
X184572Y-209897D01*
G01X182606Y-203772D02*
X175619D01*
G01X191591Y-209897D02*
Y-192397D01*
X201635Y-209897D01*
Y-192397D01*
G01X218480Y-209897D02*
X209746D01*
Y-192397D01*
X218480D01*
G01X214986Y-200855D02*
X209746D01*
G01X250859Y-200564D02*
X251733Y-199689D01*
X252388Y-198231D01*
X252825Y-196188D01*
X252388Y-194439D01*
X251515Y-193272D01*
X249986Y-192397D01*
X244091D01*
Y-209897D01*
X251296D01*
X252825Y-208731D01*
X253698Y-206980D01*
X254135Y-204939D01*
X253698Y-202897D01*
X252388Y-201147D01*
X250859Y-200564D01*
X244091D01*
G01X266613Y-209897D02*
X264866Y-209605D01*
X263338Y-208439D01*
X262028Y-206689D01*
X261154Y-204647D01*
X260718Y-202314D01*
Y-199980D01*
X261154Y-197647D01*
X262028Y-195605D01*
X263338Y-193856D01*
X264866Y-192689D01*
X266613Y-192397D01*
X268359Y-192689D01*
X269888Y-193856D01*
X271198Y-195605D01*
X272072Y-197647D01*
X272508Y-199980D01*
Y-202314D01*
X272072Y-204647D01*
X271198Y-206689D01*
X269888Y-208439D01*
X268359Y-209605D01*
X266613Y-209897D01*
G01X278654D02*
X284113Y-192397D01*
X289572Y-209897D01*
G01X287606Y-203772D02*
X280619D01*
G01X297246Y-209897D02*
Y-192397D01*
X302705D01*
X304451Y-193272D01*
X305543Y-194439D01*
X305980Y-196772D01*
X305543Y-199106D01*
X304233Y-200564D01*
X302705Y-201439D01*
X297246D01*
G01X302705D02*
X305980Y-209897D01*
G01X314310D02*
Y-192397D01*
X318676D01*
X320423Y-193272D01*
X321733Y-194439D01*
X322825Y-196188D01*
X323698Y-198231D01*
X323916Y-201147D01*
X323698Y-204064D01*
X322825Y-206106D01*
X321733Y-207856D01*
X320423Y-209022D01*
X318676Y-209897D01*
X314310D01*
G01X94686Y-164897D02*
Y-147397D01*
X100363Y-161980D01*
X106040Y-147397D01*
Y-164897D01*
G01X117863D02*
X116553Y-164605D01*
X115243Y-163439D01*
X114369Y-161397D01*
X113933Y-159064D01*
X114369Y-156730D01*
X115243Y-154689D01*
X116553Y-153522D01*
X117863Y-153231D01*
X119173Y-153522D01*
X120483Y-154689D01*
X121356Y-156730D01*
X121575Y-159064D01*
X121356Y-161397D01*
X120483Y-163439D01*
X119173Y-164605D01*
X117863Y-164897D01*
G01X139293Y-147397D02*
Y-164897D01*
G01Y-162273D02*
X138420Y-163731D01*
X137109Y-164605D01*
X135581Y-164897D01*
X133835Y-164314D01*
X132525Y-162856D01*
X131651Y-161106D01*
X131433Y-159064D01*
X131651Y-157022D01*
X132525Y-155272D01*
X133835Y-153814D01*
X135581Y-153231D01*
X137109Y-153522D01*
X138201Y-154106D01*
X139293Y-155272D01*
G01X149588Y-157022D02*
X156575D01*
X155920Y-154980D01*
X154828Y-153814D01*
X153300Y-153231D01*
X151771Y-153522D01*
X150461Y-154397D01*
X149588Y-156439D01*
X149151Y-158189D01*
Y-159939D01*
X149588Y-161689D01*
X150680Y-163439D01*
X151990Y-164605D01*
X153518Y-164897D01*
X155046Y-164314D01*
X156575Y-162564D01*
G01X170363Y-164897D02*
Y-147397D01*
G01X376163Y-209897D02*
Y-192397D01*
X373543Y-195897D01*
G01Y-209897D02*
X378783D01*
G01X389515Y-195314D02*
X390825Y-193564D01*
X392353Y-192689D01*
X394100Y-192397D01*
X396283Y-192980D01*
X397811Y-194439D01*
X398248Y-196188D01*
X398030Y-197939D01*
X397156Y-199397D01*
X392790Y-202314D01*
X390825Y-204355D01*
X389515Y-207273D01*
X389078Y-209897D01*
X398248D01*
G01X413783D02*
Y-192397D01*
X405704Y-204939D01*
X416622D01*
G01X423860Y-206397D02*
X425169Y-208439D01*
X426916Y-209605D01*
X428881Y-209897D01*
X430628Y-209605D01*
X432375Y-208147D01*
X433466Y-206397D01*
X433685Y-204647D01*
X433248Y-202606D01*
X431720Y-201147D01*
X430191Y-200564D01*
X428226D01*
G01X430191D02*
X431501Y-199689D01*
X432593Y-198231D01*
X433030Y-196481D01*
X432593Y-194730D01*
X431501Y-193272D01*
X429536Y-192397D01*
X427571Y-192689D01*
X425606Y-193856D01*
G01X442015Y-195314D02*
X443325Y-193564D01*
X444853Y-192689D01*
X446600Y-192397D01*
X448783Y-192980D01*
X450311Y-194439D01*
X450748Y-196188D01*
X450530Y-197939D01*
X449656Y-199397D01*
X445290Y-202314D01*
X443325Y-204355D01*
X442015Y-207273D01*
X441578Y-209897D01*
X450748D01*
G01X363046Y-164897D02*
Y-147397D01*
X368286D01*
X370033Y-148272D01*
X371343Y-150314D01*
X371780Y-152647D01*
X371343Y-154980D01*
X370251Y-156730D01*
X368286Y-157606D01*
X363046D01*
G01X389716Y-148856D02*
X388406Y-147980D01*
X386878Y-147397D01*
X385131D01*
X383166Y-148272D01*
X381638Y-149730D01*
X380546Y-151481D01*
X379673Y-154397D01*
X379454Y-157022D01*
X379891Y-159647D01*
X380546Y-161397D01*
X381856Y-163147D01*
X383385Y-164314D01*
X384913Y-164897D01*
X386441D01*
X387970Y-164314D01*
X389280Y-163439D01*
X390372Y-162273D01*
G01X404159Y-155564D02*
X405033Y-154689D01*
X405688Y-153231D01*
X406125Y-151188D01*
X405688Y-149439D01*
X404815Y-148272D01*
X403286Y-147397D01*
X397391D01*
Y-164897D01*
X404596D01*
X406125Y-163731D01*
X406998Y-161980D01*
X407435Y-159939D01*
X406998Y-157897D01*
X405688Y-156147D01*
X404159Y-155564D01*
X397391D01*
G01X413363Y-170730D02*
X426463D01*
G01X432391Y-164897D02*
Y-147397D01*
X442435Y-164897D01*
Y-147397D01*
G01X454913Y-164897D02*
X453166Y-164605D01*
X451638Y-163439D01*
X450328Y-161689D01*
X449454Y-159647D01*
X449018Y-157314D01*
Y-154980D01*
X449454Y-152647D01*
X450328Y-150605D01*
X451638Y-148856D01*
X453166Y-147689D01*
X454913Y-147397D01*
X456659Y-147689D01*
X458188Y-148856D01*
X459498Y-150605D01*
X460372Y-152647D01*
X460808Y-154980D01*
Y-157314D01*
X460372Y-159647D01*
X459498Y-161689D01*
X458188Y-163439D01*
X456659Y-164605D01*
X454913Y-164897D01*
G01X505754Y-147397D02*
X511213Y-164897D01*
X516672Y-147397D01*
G01X533080Y-164897D02*
X524346D01*
Y-147397D01*
X533080D01*
G01X529586Y-155855D02*
X524346D01*
G01X541846Y-164897D02*
Y-147397D01*
X547305D01*
X549051Y-148272D01*
X550143Y-149439D01*
X550580Y-151772D01*
X550143Y-154106D01*
X548833Y-155564D01*
X547305Y-156439D01*
X541846D01*
G01X547305D02*
X550580Y-164897D01*
G01X563713Y-165480D02*
X563276Y-165189D01*
Y-164605D01*
X563713Y-164314D01*
X564150Y-164605D01*
Y-165189D01*
X563713Y-165480D01*
G01X537463Y-209897D02*
Y-192397D01*
X534843Y-195897D01*
G01Y-209897D02*
X540083D01*
G01X630546Y-147397D02*
Y-164897D01*
X639280D01*
G01X656343D02*
Y-153231D01*
G01Y-155272D02*
X655470Y-154106D01*
X654159Y-153522D01*
X652631Y-153231D01*
X651103Y-153814D01*
X649793Y-154980D01*
X648919Y-156730D01*
X648483Y-159064D01*
X648919Y-161397D01*
X649793Y-163147D01*
X651103Y-164314D01*
X652631Y-164897D01*
X654159Y-164605D01*
X655470Y-163731D01*
X656343Y-162564D01*
G01X665328Y-170147D02*
X666638Y-170730D01*
X668385Y-170147D01*
X669476Y-168981D01*
X670350Y-167522D01*
X671659Y-162856D01*
X674498Y-153231D01*
G01X667511D02*
X671659Y-162856D01*
G01X684138Y-157022D02*
X691125D01*
X690470Y-154980D01*
X689378Y-153814D01*
X687850Y-153231D01*
X686321Y-153522D01*
X685011Y-154397D01*
X684138Y-156439D01*
X683701Y-158189D01*
Y-159939D01*
X684138Y-161689D01*
X685230Y-163439D01*
X686540Y-164605D01*
X688068Y-164897D01*
X689596Y-164314D01*
X691125Y-162564D01*
G01X701856Y-164897D02*
Y-153231D01*
G01Y-155564D02*
X702948Y-154397D01*
X704040Y-153522D01*
X705568Y-153231D01*
X706659Y-153522D01*
X707970Y-154397D01*
G01X719138Y-162856D02*
X720230Y-164022D01*
X721758Y-164897D01*
X723068D01*
X724378Y-164314D01*
X725251Y-163439D01*
X725688Y-162273D01*
X725470Y-160522D01*
X724596Y-159647D01*
X720666Y-157897D01*
X719793Y-155855D01*
X720230Y-154397D01*
X721103Y-153522D01*
X722413Y-153231D01*
X723723Y-153522D01*
X725033Y-154397D01*
G01X643663Y-192397D02*
Y-209897D01*
G01X638641Y-192397D02*
X648685D01*
G01X655486Y-209897D02*
Y-192397D01*
X661163Y-206980D01*
X666840Y-192397D01*
Y-209897D01*
G01X673204D02*
X678663Y-192397D01*
X684122Y-209897D01*
G01X682156Y-203772D02*
X675169D01*
G01X691578Y-207564D02*
X693325Y-209022D01*
X695290Y-209897D01*
X697036D01*
X698783Y-209022D01*
X700093Y-207564D01*
X700748Y-205522D01*
X700311Y-203481D01*
X699220Y-201730D01*
X697255Y-200564D01*
X694635Y-199980D01*
X693106Y-198814D01*
X692451Y-196772D01*
X692888Y-194730D01*
X693980Y-193272D01*
X695508Y-192397D01*
X697036D01*
X698565Y-192980D01*
X699875Y-194439D01*
G01X708860Y-209897D02*
Y-192397D01*
G01X717156D02*
X708860Y-203189D01*
G01X718466Y-209897D02*
X712571Y-198231D01*
G01X781410Y-164897D02*
Y-147397D01*
X785776D01*
X787523Y-148272D01*
X788833Y-149439D01*
X789925Y-151188D01*
X790798Y-153231D01*
X791016Y-156147D01*
X790798Y-159064D01*
X789925Y-161106D01*
X788833Y-162856D01*
X787523Y-164022D01*
X785776Y-164897D01*
X781410D01*
G01X800438Y-157022D02*
X807425D01*
X806770Y-154980D01*
X805678Y-153814D01*
X804150Y-153231D01*
X802621Y-153522D01*
X801311Y-154397D01*
X800438Y-156439D01*
X800001Y-158189D01*
Y-159939D01*
X800438Y-161689D01*
X801530Y-163439D01*
X802840Y-164605D01*
X804368Y-164897D01*
X805896Y-164314D01*
X807425Y-162564D01*
G01X817938Y-162856D02*
X819030Y-164022D01*
X820558Y-164897D01*
X821868D01*
X823178Y-164314D01*
X824051Y-163439D01*
X824488Y-162273D01*
X824270Y-160522D01*
X823396Y-159647D01*
X819466Y-157897D01*
X818593Y-155855D01*
X819030Y-154397D01*
X819903Y-153522D01*
X821213Y-153231D01*
X822523Y-153522D01*
X823833Y-154397D01*
G01X838713Y-153231D02*
Y-164897D01*
G01Y-148564D02*
X838276Y-148272D01*
Y-147689D01*
X838713Y-147397D01*
X839150Y-147689D01*
Y-148272D01*
X838713Y-148564D01*
G01X853156Y-169272D02*
X854685Y-170439D01*
X856431Y-170730D01*
X857959Y-170439D01*
X859270Y-168981D01*
X860143Y-166939D01*
Y-153231D01*
G01Y-155564D02*
X859270Y-154397D01*
X857959Y-153522D01*
X856431Y-153231D01*
X854685Y-153814D01*
X853593Y-154980D01*
X852719Y-157022D01*
X852283Y-159064D01*
X852501Y-160814D01*
X853375Y-162856D01*
X854685Y-164314D01*
X856431Y-164897D01*
X857741Y-164605D01*
X859270Y-163439D01*
X860143Y-162273D01*
G01X870001Y-164897D02*
Y-153231D01*
G01Y-156147D02*
X870875Y-154689D01*
X872185Y-153522D01*
X873931Y-153231D01*
X875459Y-153522D01*
X876770Y-154689D01*
X877425Y-156730D01*
Y-164897D01*
G01X887938Y-157022D02*
X894925D01*
X894270Y-154980D01*
X893178Y-153814D01*
X891650Y-153231D01*
X890121Y-153522D01*
X888811Y-154397D01*
X887938Y-156439D01*
X887501Y-158189D01*
Y-159939D01*
X887938Y-161689D01*
X889030Y-163439D01*
X890340Y-164605D01*
X891868Y-164897D01*
X893396Y-164314D01*
X894925Y-162564D01*
G01X905656Y-164897D02*
Y-153231D01*
G01Y-155564D02*
X906748Y-154397D01*
X907840Y-153522D01*
X909368Y-153231D01*
X910459Y-153522D01*
X911770Y-154397D01*
G01X825596Y-209897D02*
Y-192397D01*
X831055D01*
X832801Y-193272D01*
X833893Y-194439D01*
X834330Y-196772D01*
X833893Y-199106D01*
X832583Y-200564D01*
X831055Y-201439D01*
X825596D01*
G01X831055D02*
X834330Y-209897D01*
G01X847463D02*
X846153Y-209605D01*
X844843Y-208439D01*
X843969Y-206397D01*
X843533Y-204064D01*
X843969Y-201730D01*
X844843Y-199689D01*
X846153Y-198522D01*
X847463Y-198231D01*
X848773Y-198522D01*
X850083Y-199689D01*
X850956Y-201730D01*
X851175Y-204064D01*
X850956Y-206397D01*
X850083Y-208439D01*
X848773Y-209605D01*
X847463Y-209897D01*
G01X861033D02*
Y-192397D01*
G01Y-201147D02*
X862125Y-199397D01*
X863435Y-198522D01*
X864745Y-198231D01*
X866709Y-198814D01*
X868020Y-199980D01*
X868893Y-202022D01*
Y-204355D01*
X868456Y-206689D01*
X867583Y-208439D01*
X866055Y-209605D01*
X864745Y-209897D01*
X863435Y-209605D01*
X862125Y-208731D01*
X861033Y-207273D01*
G01X952413Y-209897D02*
Y-192397D01*
X949793Y-195897D01*
G01Y-209897D02*
X955033D01*
G01X969913Y-192397D02*
X968166Y-192980D01*
X966856Y-194439D01*
X965983Y-196188D01*
X965328Y-198522D01*
X965110Y-201147D01*
X965328Y-203772D01*
X965983Y-206106D01*
X966856Y-207856D01*
X968166Y-209314D01*
X969913Y-209897D01*
X971659Y-209314D01*
X972970Y-207856D01*
X973843Y-206106D01*
X974498Y-203772D01*
X974716Y-201147D01*
X974498Y-198522D01*
X973843Y-196188D01*
X972970Y-194439D01*
X971659Y-192980D01*
X969913Y-192397D01*
G01X983483Y-210480D02*
X991343Y-192397D01*
G01X1004913Y-209897D02*
Y-192397D01*
X1002293Y-195897D01*
G01Y-209897D02*
X1007533D01*
G01X1018265Y-202606D02*
X1019793Y-200564D01*
X1021103Y-199397D01*
X1022850Y-198814D01*
X1024378Y-199397D01*
X1025470Y-200564D01*
X1026343Y-202314D01*
X1026561Y-204355D01*
X1026343Y-206106D01*
X1025470Y-207856D01*
X1024159Y-209314D01*
X1022631Y-209897D01*
X1020885Y-209314D01*
X1019356Y-207564D01*
X1018483Y-204939D01*
X1018265Y-202022D01*
X1018701Y-198231D01*
X1019356Y-196188D01*
X1020448Y-194147D01*
X1021976Y-192689D01*
X1023505Y-192397D01*
X1025033Y-192980D01*
X1026125Y-194439D01*
G01X1035983Y-210480D02*
X1043843Y-192397D01*
G01X1053265Y-195314D02*
X1054575Y-193564D01*
X1056103Y-192689D01*
X1057850Y-192397D01*
X1060033Y-192980D01*
X1061561Y-194439D01*
X1061998Y-196188D01*
X1061780Y-197939D01*
X1060906Y-199397D01*
X1056540Y-202314D01*
X1054575Y-204355D01*
X1053265Y-207273D01*
X1052828Y-209897D01*
X1061998D01*
G01X1074913Y-192397D02*
X1073166Y-192980D01*
X1071856Y-194439D01*
X1070983Y-196188D01*
X1070328Y-198522D01*
X1070110Y-201147D01*
X1070328Y-203772D01*
X1070983Y-206106D01*
X1071856Y-207856D01*
X1073166Y-209314D01*
X1074913Y-209897D01*
X1076659Y-209314D01*
X1077970Y-207856D01*
X1078843Y-206106D01*
X1079498Y-203772D01*
X1079716Y-201147D01*
X1079498Y-198522D01*
X1078843Y-196188D01*
X1077970Y-194439D01*
X1076659Y-192980D01*
X1074913Y-192397D01*
G01X1092413Y-209897D02*
Y-192397D01*
X1089793Y-195897D01*
G01Y-209897D02*
X1095033D01*
G01X1105765Y-195314D02*
X1107075Y-193564D01*
X1108603Y-192689D01*
X1110350Y-192397D01*
X1112533Y-192980D01*
X1114061Y-194439D01*
X1114498Y-196188D01*
X1114280Y-197939D01*
X1113406Y-199397D01*
X1109040Y-202314D01*
X1107075Y-204355D01*
X1105765Y-207273D01*
X1105328Y-209897D01*
X1114498D01*
G01X1000110Y-164897D02*
Y-147397D01*
X1004476D01*
X1006223Y-148272D01*
X1007533Y-149439D01*
X1008625Y-151188D01*
X1009498Y-153231D01*
X1009716Y-156147D01*
X1009498Y-159064D01*
X1008625Y-161106D01*
X1007533Y-162856D01*
X1006223Y-164022D01*
X1004476Y-164897D01*
X1000110D01*
G01X1026343D02*
Y-153231D01*
G01Y-155272D02*
X1025470Y-154106D01*
X1024159Y-153522D01*
X1022631Y-153231D01*
X1021103Y-153814D01*
X1019793Y-154980D01*
X1018919Y-156730D01*
X1018483Y-159064D01*
X1018919Y-161397D01*
X1019793Y-163147D01*
X1021103Y-164314D01*
X1022631Y-164897D01*
X1024159Y-164605D01*
X1025470Y-163731D01*
X1026343Y-162564D01*
G01X1039913Y-147397D02*
Y-164897D01*
G01X1036856Y-153231D02*
X1042970D01*
G01X1054138Y-157022D02*
X1061125D01*
X1060470Y-154980D01*
X1059378Y-153814D01*
X1057850Y-153231D01*
X1056321Y-153522D01*
X1055011Y-154397D01*
X1054138Y-156439D01*
X1053701Y-158189D01*
Y-159939D01*
X1054138Y-161689D01*
X1055230Y-163439D01*
X1056540Y-164605D01*
X1058068Y-164897D01*
X1059596Y-164314D01*
X1061125Y-162564D01*
G54D79*
X242299Y1117109D03*
Y1128271D03*
M02*
